FILE_TYPE = MACRO_DRAWING;
SET COLOR_WIRE YELLOW;
SET COLOR_PROP ORANGE;
SET COLOR_DOT WHITE;
SET COLOR_ARC YELLOW;
SET COLOR_BODY GREEN;
SET COLOR_NOTE PURPLE;
SET PROP_DISPLAY VALUE;
SET PAGE_NUMBER P263;
FORCEADD UNIVERSAL_GND..1
(-4150 5000);
FORCEPROP 3 LASTPIN (-4150 5050) SIG_NAME GND\g
J 0
(-4140 5060);
DISPLAY 0.659574 (-4140 5060);
PAINT MONO (-4140 5060);
DISPLAY INVISIBLE (-4140 5060);
FORCEPROP 2 LAST CDS_LIB pure_quanta_power
J 0
(-4150 5000);
DISPLAY INVISIBLE (-4150 5000);
FORCEPROP 1 LAST HDL_POWER GND
J 1
(-4125 4925);
DISPLAY 0.872340 (-4125 4925);
PAINT GREEN (-4125 4925);
DISPLAY INVISIBLE (-4125 4925);
FORCEPROP 1 LAST PATH I114
J 0
(-4075 5000);
DISPLAY 0.872340 (-4075 5000);
PAINT AQUA (-4075 5000);
DISPLAY INVISIBLE (-4075 5000);
FORCEADD Q_CAP..1
R 2
(-4150 5200);
FORCEPROP 1 LAST LOCATION C1074
J 2
(-3975 5325);
DISPLAY 0.638298 (-3975 5325);
FORCEPROP 0 LAST $SEC 1
J 0
(-4200 5350);
DISPLAY 0.680851 (-4200 5350);
PAINT MONO (-4200 5350);
DISPLAY INVISIBLE (-4200 5350);
FORCEPROP 0 LAST CDS_SEC 1
J 0
(-4200 5350);
DISPLAY 1.021277 (-4200 5350);
DISPLAY INVISIBLE (-4200 5350);
FORCEPROP 1 LASTPIN (-4150 5300) $PN 1
J 2
(-4160 5280);
DISPLAY 0.787234 (-4160 5280);
PAINT MONO (-4160 5280);
FORCEPROP 1 LASTPIN (-4150 5100) $PN 2
J 2
(-4160 5080);
DISPLAY 0.787234 (-4160 5080);
PAINT MONO (-4160 5080);
FORCEPROP 1 LAST PACK_TYPE 0402
J 2
(-3975 5025);
DISPLAY 0.510638 (-3975 5025);
FORCEPROP 1 LAST MATERIAL X7R
J 2
(-4000 5125);
DISPLAY 0.510638 (-4000 5125);
FORCEPROP 1 LAST TOLERANCE 10%
J 2
(-4000 5175);
DISPLAY 0.510638 (-4000 5175);
FORCEPROP 1 LAST VOLTAGE 25V
J 2
(-4000 5225);
DISPLAY 0.510638 (-4000 5225);
FORCEPROP 1 LAST VALUE 0.1UF
J 2
(-3975 5275);
DISPLAY 0.510638 (-3975 5275);
FORCEPROP 2 LAST CDS_LIB pure_quanta
J 0
(-4150 5200);
DISPLAY INVISIBLE (-4150 5200);
FORCEPROP 1 LAST PATH I115
J 2
(-4200 5350);
DISPLAY 0.978723 (-4200 5350);
PAINT WHITE (-4200 5350);
DISPLAY INVISIBLE (-4200 5350);
FORCEPROP 1 LAST PART_NUMBER CH4104K1B00
J 2
(-3850 5075);
DISPLAY 0.510638 (-3850 5075);
DISPLAY INVISIBLE (-3850 5075);
FORCEADD OFFPAGE..2
(-3375 825);
FORCEPROP 2 LAST $XR0 259 
J 0
(-3186 825);
DISPLAY 0.638298 (-3186 825);
PAINT MONO (-3186 825);
FORCEPROP 2 LAST CDS_LIB standard
J 0
(-3375 825);
DISPLAY INVISIBLE (-3375 825);
FORCEPROP 1 LAST OFFPAGE TRUE
J 0
(-3050 700);
DISPLAY 0.872340 (-3050 700);
DISPLAY INVISIBLE (-3050 700);
FORCEPROP 1 LAST COMMENT_BODY TRUE
J 0
(-3420 730);
DISPLAY 0.872340 (-3420 730);
PAINT GREEN (-3420 730);
DISPLAY INVISIBLE (-3420 730);
FORCEPROP 2 LAST PATH I116
J 0
(-3175 875);
DISPLAY 0.680851 (-3175 875);
DISPLAY INVISIBLE (-3175 875);
FORCEADD OFFPAGE..2
(-3375 925);
FORCEPROP 2 LAST $XR0 259 
J 0
(-3186 925);
DISPLAY 0.638298 (-3186 925);
PAINT MONO (-3186 925);
FORCEPROP 2 LAST CDS_LIB standard
J 0
(-3375 925);
DISPLAY INVISIBLE (-3375 925);
FORCEPROP 1 LAST OFFPAGE TRUE
J 0
(-3050 800);
DISPLAY 0.872340 (-3050 800);
DISPLAY INVISIBLE (-3050 800);
FORCEPROP 1 LAST COMMENT_BODY TRUE
J 0
(-3420 830);
DISPLAY 0.872340 (-3420 830);
PAINT GREEN (-3420 830);
DISPLAY INVISIBLE (-3420 830);
FORCEPROP 2 LAST PATH I117
J 0
(-3175 975);
DISPLAY 0.680851 (-3175 975);
DISPLAY INVISIBLE (-3175 975);
FORCEADD UNIVERSAL_GND..1
(-3425 1525);
FORCEPROP 3 LASTPIN (-3425 1575) SIG_NAME GND\g
J 0
(-3415 1585);
DISPLAY 0.659574 (-3415 1585);
PAINT MONO (-3415 1585);
DISPLAY INVISIBLE (-3415 1585);
FORCEPROP 2 LAST CDS_LIB pure_quanta_power
J 0
(-3425 1525);
DISPLAY INVISIBLE (-3425 1525);
FORCEPROP 1 LAST HDL_POWER GND
J 1
(-3400 1450);
DISPLAY 0.872340 (-3400 1450);
PAINT GREEN (-3400 1450);
DISPLAY INVISIBLE (-3400 1450);
FORCEPROP 1 LAST PATH I118
J 0
(-3350 1525);
DISPLAY 0.872340 (-3350 1525);
PAINT AQUA (-3350 1525);
DISPLAY INVISIBLE (-3350 1525);
FORCEADD Q_RES..2
(-3425 1850);
FORCEPROP 1 LAST LOCATION R1268
J 0
(-3380 1975);
DISPLAY 0.808511 (-3380 1975);
FORCEPROP 0 LAST $SEC 1
J 0
(-3375 2025);
DISPLAY 0.680851 (-3375 2025);
PAINT MONO (-3375 2025);
DISPLAY INVISIBLE (-3375 2025);
FORCEPROP 0 LAST CDS_SEC 1
J 0
(-3375 2025);
DISPLAY 1.021277 (-3375 2025);
DISPLAY INVISIBLE (-3375 2025);
FORCEPROP 1 LASTPIN (-3425 1950) $PN 1
J 0
(-3420 1912);
DISPLAY 0.787234 (-3420 1912);
PAINT MONO (-3420 1912);
FORCEPROP 1 LASTPIN (-3425 1750) $PN 2
J 0
(-3420 1760);
DISPLAY 0.787234 (-3420 1760);
PAINT MONO (-3420 1760);
FORCEPROP 1 LAST VALUE 4.7K
J 0
(-3380 1925);
DISPLAY 0.638298 (-3380 1925);
FORCEPROP 1 LAST MATERIAL EMPTY
J 0
(-3385 1775);
DISPLAY 0.638298 (-3385 1775);
PAINT RED (-3385 1775);
FORCEPROP 1 LAST WATTAGE 1/16W
J 0
(-3385 1825);
DISPLAY 0.638298 (-3385 1825);
FORCEPROP 1 LAST TOLERANCE 1%
J 0
(-3380 1875);
DISPLAY 0.638298 (-3380 1875);
FORCEPROP 0 LAST ROOM ADC_TI_BOM1
J 0
(-3375 2075);
DISPLAY 0.680851 (-3375 2075);
PAINT RED (-3375 2075);
FORCEPROP 1 LAST PACK_TYPE 0402LF
J 0
(-3385 1675);
DISPLAY 0.638298 (-3385 1675);
FORCEPROP 2 LAST CDS_LIB pure_quanta
J 0
(-3425 1850);
DISPLAY INVISIBLE (-3425 1850);
FORCEPROP 1 LAST PATH I119
J 0
(-3375 2025);
DISPLAY 0.978723 (-3375 2025);
PAINT WHITE (-3375 2025);
DISPLAY INVISIBLE (-3375 2025);
FORCEPROP 1 LAST PART_NUMBER CS24702FB06
J 0
(-3385 1725);
DISPLAY 0.638298 (-3385 1725);
DISPLAY INVISIBLE (-3385 1725);
FORCEADD Q_RES..2
(-9025 5475);
FORCEPROP 1 LAST LOCATION R1226
J 0
(-8975 5600);
DISPLAY 0.510638 (-8975 5600);
FORCEPROP 2 LAST $SEC 1
J 0
(-8975 5700);
DISPLAY 0.680851 (-8975 5700);
PAINT MONO (-8975 5700);
DISPLAY INVISIBLE (-8975 5700);
FORCEPROP 0 LAST CDS_SEC 1
J 0
(-8975 5625);
DISPLAY 1.021277 (-8975 5625);
DISPLAY INVISIBLE (-8975 5625);
FORCEPROP 1 LASTPIN (-9025 5575) $PN 1
J 0
(-9020 5537);
DISPLAY 0.787234 (-9020 5537);
PAINT MONO (-9020 5537);
FORCEPROP 1 LASTPIN (-9025 5375) $PN 2
J 0
(-9020 5385);
DISPLAY 0.787234 (-9020 5385);
PAINT MONO (-9020 5385);
FORCEPROP 1 LAST TOLERANCE 1%
J 0
(-8975 5500);
DISPLAY 0.510638 (-8975 5500);
FORCEPROP 1 LAST MATERIAL CHIP
J 0
(-8980 5400);
DISPLAY 0.510638 (-8980 5400);
FORCEPROP 1 LAST WATTAGE 1/16W
J 0
(-8980 5450);
DISPLAY 0.510638 (-8980 5450);
FORCEPROP 1 LAST VALUE 9.09K
J 0
(-8975 5550);
DISPLAY 0.510638 (-8975 5550);
FORCEPROP 1 LAST PACK_TYPE 0402LF
J 0
(-8970 5300);
DISPLAY 0.510638 (-8970 5300);
FORCEPROP 2 LAST CDS_LIB pure_quanta
J 0
(-9025 5475);
DISPLAY INVISIBLE (-9025 5475);
FORCEPROP 1 LAST PATH I12
J 0
(-8975 5650);
DISPLAY 0.978723 (-8975 5650);
PAINT WHITE (-8975 5650);
DISPLAY INVISIBLE (-8975 5650);
FORCEPROP 1 LAST PART_NUMBER CS29092FB05
J 0
(-8980 5350);
DISPLAY 0.510638 (-8980 5350);
DISPLAY INVISIBLE (-8980 5350);
FORCEADD OFFPAGE..1
(-2500 850);
FORCEPROP 2 LAST $XR1 259 
J 0
(-2902 850);
DISPLAY 0.638298 (-2902 850);
PAINT MONO (-2902 850);
FORCEPROP 2 LAST $XR0 253 
J 0
(-2782 850);
DISPLAY 0.638298 (-2782 850);
PAINT MONO (-2782 850);
FORCEPROP 2 LAST CDS_LIB standard
J 0
(-2500 850);
PAINT MONO (-2500 850);
DISPLAY INVISIBLE (-2500 850);
FORCEPROP 1 LAST OFFPAGE TRUE
J 0
(-2175 725);
DISPLAY 0.872340 (-2175 725);
PAINT GREEN (-2175 725);
DISPLAY INVISIBLE (-2175 725);
FORCEPROP 1 LAST COMMENT_BODY TRUE
J 0
(-2375 750);
DISPLAY 0.872340 (-2375 750);
PAINT GREEN (-2375 750);
DISPLAY INVISIBLE (-2375 750);
FORCEPROP 2 LAST PATH I120
J 0
(-2800 900);
DISPLAY 0.680851 (-2800 900);
DISPLAY INVISIBLE (-2800 900);
FORCEADD OFFPAGE..3
R 2
(-2500 900);
FORCEPROP 2 LAST $XR1 259 
J 0
(-2900 900);
DISPLAY 0.638298 (-2900 900);
PAINT MONO (-2900 900);
FORCEPROP 2 LAST $XR0 253 
J 0
(-2780 900);
DISPLAY 0.638298 (-2780 900);
PAINT MONO (-2780 900);
FORCEPROP 2 LAST CDS_LIB standard
J 0
(-2500 900);
PAINT MONO (-2500 900);
DISPLAY INVISIBLE (-2500 900);
FORCEPROP 1 LAST OFFPAGE TRUE
J 2
(-2825 775);
DISPLAY 0.872340 (-2825 775);
DISPLAY INVISIBLE (-2825 775);
FORCEPROP 1 LAST COMMENT_BODY TRUE
J 2
(-2450 800);
DISPLAY 0.872340 (-2450 800);
PAINT GREEN (-2450 800);
DISPLAY INVISIBLE (-2450 800);
FORCEPROP 2 LAST PATH I121
J 0
(-2800 950);
DISPLAY 0.680851 (-2800 950);
DISPLAY INVISIBLE (-2800 950);
FORCEADD OFFPAGE..4
R 2
(-2700 1525);
FORCEPROP 2 LAST $XR0 259 
J 0
(-2952 1525);
DISPLAY 0.638298 (-2952 1525);
PAINT MONO (-2952 1525);
FORCEPROP 2 LAST CDS_LIB standard
J 2
(-2700 1525);
DISPLAY INVISIBLE (-2700 1525);
FORCEPROP 1 LAST OFFPAGE TRUE
J 2
(-3025 1400);
DISPLAY 0.872340 (-3025 1400);
DISPLAY INVISIBLE (-3025 1400);
FORCEPROP 1 LAST COMMENT_BODY TRUE
J 2
(-2675 1425);
DISPLAY 0.872340 (-2675 1425);
PAINT GREEN (-2675 1425);
DISPLAY INVISIBLE (-2675 1425);
FORCEPROP 2 LAST PATH I122
J 0
(-2975 1575);
DISPLAY 0.680851 (-2975 1575);
DISPLAY INVISIBLE (-2975 1575);
FORCEADD OFFPAGE..4
R 2
(-2700 1575);
FORCEPROP 2 LAST $XR0 259 
J 0
(-2952 1575);
DISPLAY 0.638298 (-2952 1575);
PAINT MONO (-2952 1575);
FORCEPROP 2 LAST CDS_LIB standard
J 2
(-2700 1575);
DISPLAY INVISIBLE (-2700 1575);
FORCEPROP 1 LAST OFFPAGE TRUE
J 2
(-3025 1450);
DISPLAY 0.872340 (-3025 1450);
DISPLAY INVISIBLE (-3025 1450);
FORCEPROP 1 LAST COMMENT_BODY TRUE
J 2
(-2675 1475);
DISPLAY 0.872340 (-2675 1475);
PAINT GREEN (-2675 1475);
DISPLAY INVISIBLE (-2675 1475);
FORCEPROP 2 LAST PATH I123
J 0
(-2975 1625);
DISPLAY 0.680851 (-2975 1625);
DISPLAY INVISIBLE (-2975 1625);
FORCEADD OFFPAGE..4
R 2
(-2700 1625);
FORCEPROP 2 LAST $XR0 259 
J 0
(-2952 1625);
DISPLAY 0.638298 (-2952 1625);
PAINT MONO (-2952 1625);
FORCEPROP 2 LAST CDS_LIB standard
J 2
(-2700 1625);
DISPLAY INVISIBLE (-2700 1625);
FORCEPROP 1 LAST OFFPAGE TRUE
J 2
(-3025 1500);
DISPLAY 0.872340 (-3025 1500);
DISPLAY INVISIBLE (-3025 1500);
FORCEPROP 1 LAST COMMENT_BODY TRUE
J 2
(-2675 1525);
DISPLAY 0.872340 (-2675 1525);
PAINT GREEN (-2675 1525);
DISPLAY INVISIBLE (-2675 1525);
FORCEPROP 2 LAST PATH I124
J 0
(-2975 1675);
DISPLAY 0.680851 (-2975 1675);
DISPLAY INVISIBLE (-2975 1675);
FORCEADD OFFPAGE..4
R 2
(-2700 1825);
FORCEPROP 2 LAST $XR0 259 
J 0
(-2952 1825);
DISPLAY 0.638298 (-2952 1825);
PAINT MONO (-2952 1825);
FORCEPROP 2 LAST CDS_LIB standard
J 2
(-2700 1825);
DISPLAY INVISIBLE (-2700 1825);
FORCEPROP 1 LAST OFFPAGE TRUE
J 2
(-3025 1700);
DISPLAY 0.872340 (-3025 1700);
DISPLAY INVISIBLE (-3025 1700);
FORCEPROP 1 LAST COMMENT_BODY TRUE
J 2
(-2675 1725);
DISPLAY 0.872340 (-2675 1725);
PAINT GREEN (-2675 1725);
DISPLAY INVISIBLE (-2675 1725);
FORCEPROP 2 LAST PATH I125
J 0
(-2975 1875);
DISPLAY 0.680851 (-2975 1875);
DISPLAY INVISIBLE (-2975 1875);
FORCEADD OFFPAGE..4
R 2
(-2700 1725);
FORCEPROP 2 LAST $XR0 259 
J 0
(-2952 1725);
DISPLAY 0.638298 (-2952 1725);
PAINT MONO (-2952 1725);
FORCEPROP 2 LAST CDS_LIB standard
J 2
(-2700 1725);
DISPLAY INVISIBLE (-2700 1725);
FORCEPROP 1 LAST OFFPAGE TRUE
J 2
(-3025 1600);
DISPLAY 0.872340 (-3025 1600);
DISPLAY INVISIBLE (-3025 1600);
FORCEPROP 1 LAST COMMENT_BODY TRUE
J 2
(-2675 1625);
DISPLAY 0.872340 (-2675 1625);
PAINT GREEN (-2675 1625);
DISPLAY INVISIBLE (-2675 1625);
FORCEPROP 2 LAST PATH I126
J 0
(-2975 1775);
DISPLAY 0.680851 (-2975 1775);
DISPLAY INVISIBLE (-2975 1775);
FORCEADD OFFPAGE..4
R 2
(-2700 1775);
FORCEPROP 2 LAST $XR0 259 
J 0
(-2952 1775);
DISPLAY 0.638298 (-2952 1775);
PAINT MONO (-2952 1775);
FORCEPROP 2 LAST CDS_LIB standard
J 2
(-2700 1775);
DISPLAY INVISIBLE (-2700 1775);
FORCEPROP 1 LAST OFFPAGE TRUE
J 2
(-3025 1650);
DISPLAY 0.872340 (-3025 1650);
DISPLAY INVISIBLE (-3025 1650);
FORCEPROP 1 LAST COMMENT_BODY TRUE
J 2
(-2675 1675);
DISPLAY 0.872340 (-2675 1675);
PAINT GREEN (-2675 1675);
DISPLAY INVISIBLE (-2675 1675);
FORCEPROP 2 LAST PATH I127
J 0
(-2975 1825);
DISPLAY 0.680851 (-2975 1825);
DISPLAY INVISIBLE (-2975 1825);
FORCEADD OFFPAGE..4
R 2
(-2700 1675);
FORCEPROP 2 LAST $XR0 259 
J 0
(-2952 1675);
DISPLAY 0.638298 (-2952 1675);
PAINT MONO (-2952 1675);
FORCEPROP 2 LAST CDS_LIB standard
J 2
(-2700 1675);
DISPLAY INVISIBLE (-2700 1675);
FORCEPROP 1 LAST OFFPAGE TRUE
J 2
(-3025 1550);
DISPLAY 0.872340 (-3025 1550);
DISPLAY INVISIBLE (-3025 1550);
FORCEPROP 1 LAST COMMENT_BODY TRUE
J 2
(-2675 1575);
DISPLAY 0.872340 (-2675 1575);
PAINT GREEN (-2675 1575);
DISPLAY INVISIBLE (-2675 1575);
FORCEPROP 2 LAST PATH I128
J 0
(-2975 1725);
DISPLAY 0.680851 (-2975 1725);
DISPLAY INVISIBLE (-2975 1725);
FORCEADD OFFPAGE..4
R 2
(-2700 1875);
FORCEPROP 2 LAST $XR0 259 
J 0
(-2952 1875);
DISPLAY 0.638298 (-2952 1875);
PAINT MONO (-2952 1875);
FORCEPROP 2 LAST CDS_LIB standard
J 2
(-2700 1875);
DISPLAY INVISIBLE (-2700 1875);
FORCEPROP 1 LAST OFFPAGE TRUE
J 2
(-3025 1750);
DISPLAY 0.872340 (-3025 1750);
DISPLAY INVISIBLE (-3025 1750);
FORCEPROP 1 LAST COMMENT_BODY TRUE
J 2
(-2675 1775);
DISPLAY 0.872340 (-2675 1775);
PAINT GREEN (-2675 1775);
DISPLAY INVISIBLE (-2675 1775);
FORCEPROP 2 LAST PATH I129
J 0
(-2975 1925);
DISPLAY 0.680851 (-2975 1925);
DISPLAY INVISIBLE (-2975 1925);
FORCEADD Q_RES..2
(-9025 6025);
FORCEPROP 1 LAST LOCATION R1238
J 0
(-8980 6150);
DISPLAY 0.638298 (-8980 6150);
FORCEPROP 0 LAST $SEC 1
J 0
(-8975 6200);
DISPLAY 0.680851 (-8975 6200);
PAINT MONO (-8975 6200);
DISPLAY INVISIBLE (-8975 6200);
FORCEPROP 0 LAST CDS_SEC 1
J 0
(-8975 6175);
DISPLAY 1.021277 (-8975 6175);
DISPLAY INVISIBLE (-8975 6175);
FORCEPROP 1 LASTPIN (-9025 6125) $PN 1
J 0
(-9020 6087);
DISPLAY 0.787234 (-9020 6087);
PAINT MONO (-9020 6087);
FORCEPROP 1 LASTPIN (-9025 5925) $PN 2
J 0
(-9020 5935);
DISPLAY 0.787234 (-9020 5935);
PAINT MONO (-9020 5935);
FORCEPROP 1 LAST WATTAGE 1/16W
J 0
(-8985 6000);
DISPLAY 0.510638 (-8985 6000);
FORCEPROP 1 LAST MATERIAL CHIP
J 0
(-8985 5950);
DISPLAY 0.510638 (-8985 5950);
FORCEPROP 1 LAST PACK_TYPE 0402LF
J 0
(-8985 5850);
DISPLAY 0.510638 (-8985 5850);
FORCEPROP 1 LAST TOLERANCE 1%
J 0
(-8980 6050);
DISPLAY 0.510638 (-8980 6050);
FORCEPROP 1 LAST VALUE 18K
J 0
(-8980 6100);
DISPLAY 0.510638 (-8980 6100);
FORCEPROP 2 LAST CDS_LIB pure_quanta
J 0
(-9025 6025);
DISPLAY INVISIBLE (-9025 6025);
FORCEPROP 1 LAST PATH I13
J 0
(-8975 6200);
DISPLAY 0.978723 (-8975 6200);
PAINT WHITE (-8975 6200);
DISPLAY INVISIBLE (-8975 6200);
FORCEPROP 1 LAST PART_NUMBER CS31802FB04
J 0
(-8985 5900);
DISPLAY 0.510638 (-8985 5900);
DISPLAY INVISIBLE (-8985 5900);
FORCEADD Q_CAP..1
(-3800 2350);
FORCEPROP 1 LAST LOCATION C1095
J 0
(-3750 2450);
DISPLAY 0.978723 (-3750 2450);
FORCEPROP 0 LAST $SEC 1
J 0
(-3750 2500);
DISPLAY 0.680851 (-3750 2500);
PAINT MONO (-3750 2500);
DISPLAY INVISIBLE (-3750 2500);
FORCEPROP 0 LAST CDS_SEC 1
J 0
(-3750 2500);
DISPLAY 1.021277 (-3750 2500);
DISPLAY INVISIBLE (-3750 2500);
FORCEPROP 1 LASTPIN (-3800 2450) $PN 1
J 0
(-3790 2430);
DISPLAY 0.787234 (-3790 2430);
PAINT MONO (-3790 2430);
FORCEPROP 1 LASTPIN (-3800 2250) $PN 2
J 0
(-3790 2230);
DISPLAY 0.787234 (-3790 2230);
PAINT MONO (-3790 2230);
FORCEPROP 1 LAST TOLERANCE 10%
J 0
(-3750 2300);
DISPLAY 0.510638 (-3750 2300);
FORCEPROP 1 LAST PACK_TYPE 0402
J 0
(-3750 2150);
DISPLAY 0.510638 (-3750 2150);
FORCEPROP 1 LAST MATERIAL X7R
J 0
(-3750 2250);
DISPLAY 0.510638 (-3750 2250);
PAINT RED (-3750 2250);
FORCEPROP 1 LAST VALUE 0.1UF
J 0
(-3750 2400);
DISPLAY 0.510638 (-3750 2400);
FORCEPROP 1 LAST VOLTAGE 25V
J 0
(-3750 2350);
DISPLAY 0.510638 (-3750 2350);
FORCEPROP 0 LAST ROOM ADC_TI_BOM1
J 0
(-3775 2100);
DISPLAY 0.680851 (-3775 2100);
PAINT RED (-3775 2100);
FORCEPROP 2 LAST CDS_LIB pure_quanta
J 0
(-3800 2350);
DISPLAY INVISIBLE (-3800 2350);
FORCEPROP 1 LAST PATH I130
J 0
(-3750 2500);
DISPLAY 0.978723 (-3750 2500);
PAINT WHITE (-3750 2500);
DISPLAY INVISIBLE (-3750 2500);
FORCEPROP 1 LAST PART_NUMBER CH4104K1B00
J 0
(-3750 2200);
DISPLAY 0.510638 (-3750 2200);
DISPLAY INVISIBLE (-3750 2200);
FORCEADD Q_RES..2
(-3425 2350);
FORCEPROP 1 LAST LOCATION R1267
J 0
(-3375 2400);
DISPLAY 0.638298 (-3375 2400);
FORCEPROP 0 LAST $SEC 1
J 0
(-3375 2525);
DISPLAY 0.680851 (-3375 2525);
PAINT MONO (-3375 2525);
DISPLAY INVISIBLE (-3375 2525);
FORCEPROP 0 LAST CDS_SEC 1
J 0
(-3375 2525);
DISPLAY 1.021277 (-3375 2525);
DISPLAY INVISIBLE (-3375 2525);
FORCEPROP 1 LASTPIN (-3425 2450) $PN 1
J 0
(-3420 2412);
DISPLAY 0.787234 (-3420 2412);
PAINT MONO (-3420 2412);
FORCEPROP 1 LASTPIN (-3425 2250) $PN 2
J 0
(-3420 2260);
DISPLAY 0.787234 (-3420 2260);
PAINT MONO (-3420 2260);
FORCEPROP 0 LAST ROOM ADC_TI_BOM1
J 0
(-3375 2450);
DISPLAY 0.680851 (-3375 2450);
PAINT RED (-3375 2450);
FORCEPROP 1 LAST VALUE 4.7K
J 0
(-3375 2350);
DISPLAY 0.510638 (-3375 2350);
FORCEPROP 1 LAST TOLERANCE 1%
J 0
(-3375 2300);
DISPLAY 0.510638 (-3375 2300);
FORCEPROP 1 LAST MATERIAL EMPTY
J 0
(-3375 2200);
DISPLAY 0.510638 (-3375 2200);
PAINT RED (-3375 2200);
FORCEPROP 1 LAST WATTAGE 1/16W
J 0
(-3375 2250);
DISPLAY 0.510638 (-3375 2250);
FORCEPROP 1 LAST PACK_TYPE 0402LF
J 0
(-3375 2150);
DISPLAY 0.510638 (-3375 2150);
FORCEPROP 2 LAST CDS_LIB pure_quanta
J 0
(-3425 2350);
DISPLAY INVISIBLE (-3425 2350);
FORCEPROP 1 LAST PATH I131
J 0
(-3375 2525);
DISPLAY 0.978723 (-3375 2525);
PAINT WHITE (-3375 2525);
DISPLAY INVISIBLE (-3375 2525);
FORCEPROP 1 LAST PART_NUMBER CS24702FB06
J 0
(-3375 2175);
DISPLAY 0.510638 (-3375 2175);
DISPLAY INVISIBLE (-3375 2175);
FORCEADD OFFPAGE..3
R 2
(-3350 3550);
FORCEPROP 2 LAST $XR1 259 
J 0
(-3750 3550);
DISPLAY 0.638298 (-3750 3550);
PAINT MONO (-3750 3550);
FORCEPROP 2 LAST $XR0 253 
J 0
(-3630 3550);
DISPLAY 0.638298 (-3630 3550);
PAINT MONO (-3630 3550);
FORCEPROP 2 LAST CDS_LIB standard
J 0
(-3350 3550);
PAINT MONO (-3350 3550);
DISPLAY INVISIBLE (-3350 3550);
FORCEPROP 1 LAST OFFPAGE TRUE
J 2
(-3675 3425);
DISPLAY 0.872340 (-3675 3425);
DISPLAY INVISIBLE (-3675 3425);
FORCEPROP 1 LAST COMMENT_BODY TRUE
J 2
(-3300 3450);
DISPLAY 0.872340 (-3300 3450);
PAINT GREEN (-3300 3450);
DISPLAY INVISIBLE (-3300 3450);
FORCEPROP 2 LAST PATH I132
J 0
(-3625 3600);
DISPLAY 0.680851 (-3625 3600);
DISPLAY INVISIBLE (-3625 3600);
FORCEADD OFFPAGE..1
(-3350 3500);
FORCEPROP 2 LAST $XR1 259 
J 0
(-3752 3500);
DISPLAY 0.638298 (-3752 3500);
PAINT MONO (-3752 3500);
FORCEPROP 2 LAST $XR0 253 
J 0
(-3632 3500);
DISPLAY 0.638298 (-3632 3500);
PAINT MONO (-3632 3500);
FORCEPROP 2 LAST CDS_LIB standard
J 0
(-3350 3500);
PAINT MONO (-3350 3500);
DISPLAY INVISIBLE (-3350 3500);
FORCEPROP 1 LAST OFFPAGE TRUE
J 0
(-3025 3375);
DISPLAY 0.872340 (-3025 3375);
PAINT GREEN (-3025 3375);
DISPLAY INVISIBLE (-3025 3375);
FORCEPROP 1 LAST COMMENT_BODY TRUE
J 0
(-3225 3400);
DISPLAY 0.872340 (-3225 3400);
PAINT GREEN (-3225 3400);
DISPLAY INVISIBLE (-3225 3400);
FORCEPROP 2 LAST PATH I133
J 0
(-3625 3550);
DISPLAY 0.680851 (-3625 3550);
DISPLAY INVISIBLE (-3625 3550);
FORCEADD OFFPAGE..4
R 2
(-2700 2025);
FORCEPROP 2 LAST $XR0 259 
J 0
(-2952 2025);
DISPLAY 0.638298 (-2952 2025);
PAINT MONO (-2952 2025);
FORCEPROP 2 LAST CDS_LIB standard
J 2
(-2700 2025);
DISPLAY INVISIBLE (-2700 2025);
FORCEPROP 1 LAST OFFPAGE TRUE
J 2
(-3025 1900);
DISPLAY 0.872340 (-3025 1900);
DISPLAY INVISIBLE (-3025 1900);
FORCEPROP 1 LAST COMMENT_BODY TRUE
J 2
(-2675 1925);
DISPLAY 0.872340 (-2675 1925);
PAINT GREEN (-2675 1925);
DISPLAY INVISIBLE (-2675 1925);
FORCEPROP 2 LAST PATH I134
J 0
(-2975 2075);
DISPLAY 0.680851 (-2975 2075);
DISPLAY INVISIBLE (-2975 2075);
FORCEADD OFFPAGE..4
R 2
(-2700 1975);
FORCEPROP 2 LAST $XR0 259 
J 0
(-2952 1975);
DISPLAY 0.638298 (-2952 1975);
PAINT MONO (-2952 1975);
FORCEPROP 2 LAST CDS_LIB standard
J 2
(-2700 1975);
DISPLAY INVISIBLE (-2700 1975);
FORCEPROP 1 LAST OFFPAGE TRUE
J 2
(-3025 1850);
DISPLAY 0.872340 (-3025 1850);
DISPLAY INVISIBLE (-3025 1850);
FORCEPROP 1 LAST COMMENT_BODY TRUE
J 2
(-2675 1875);
DISPLAY 0.872340 (-2675 1875);
PAINT GREEN (-2675 1875);
DISPLAY INVISIBLE (-2675 1875);
FORCEPROP 2 LAST PATH I135
J 0
(-2975 2025);
DISPLAY 0.680851 (-2975 2025);
DISPLAY INVISIBLE (-2975 2025);
FORCEADD OFFPAGE..3
R 2
(-2700 2225);
FORCEPROP 2 LAST $XR0 259 
J 0
(-2980 2225);
DISPLAY 0.638298 (-2980 2225);
PAINT MONO (-2980 2225);
FORCEPROP 2 LAST CDS_LIB standard
J 2
(-2700 2225);
DISPLAY INVISIBLE (-2700 2225);
FORCEPROP 1 LAST OFFPAGE TRUE
J 2
(-3025 2100);
DISPLAY 0.872340 (-3025 2100);
PAINT GREEN (-3025 2100);
DISPLAY INVISIBLE (-3025 2100);
FORCEPROP 1 LAST COMMENT_BODY TRUE
J 2
(-2650 2125);
DISPLAY 0.872340 (-2650 2125);
PAINT GREEN (-2650 2125);
DISPLAY INVISIBLE (-2650 2125);
FORCEPROP 2 LAST PATH I136
J 0
(-3000 2275);
DISPLAY 0.680851 (-3000 2275);
DISPLAY INVISIBLE (-3000 2275);
FORCEADD OFFPAGE..4
R 2
(-2700 2275);
FORCEPROP 2 LAST $XR0 259 
J 0
(-2952 2275);
DISPLAY 0.638298 (-2952 2275);
PAINT MONO (-2952 2275);
FORCEPROP 2 LAST CDS_LIB standard
J 2
(-2700 2275);
DISPLAY INVISIBLE (-2700 2275);
FORCEPROP 1 LAST OFFPAGE TRUE
J 2
(-3025 2150);
DISPLAY 0.872340 (-3025 2150);
DISPLAY INVISIBLE (-3025 2150);
FORCEPROP 1 LAST COMMENT_BODY TRUE
J 2
(-2675 2175);
DISPLAY 0.872340 (-2675 2175);
PAINT GREEN (-2675 2175);
DISPLAY INVISIBLE (-2675 2175);
FORCEPROP 2 LAST PATH I137
J 0
(-2975 2325);
DISPLAY 0.680851 (-2975 2325);
DISPLAY INVISIBLE (-2975 2325);
FORCEADD Q_RES..1
(-2350 3550);
FORCEPROP 1 LAST LOCATION R1227
J 0
(-2550 3550);
DISPLAY 0.510638 (-2550 3550);
FORCEPROP 0 LAST $SEC 1
J 0
(-2125 3575);
DISPLAY 0.680851 (-2125 3575);
PAINT MONO (-2125 3575);
DISPLAY INVISIBLE (-2125 3575);
FORCEPROP 0 LAST CDS_SEC 1
J 0
(-2125 3575);
DISPLAY 1.021277 (-2125 3575);
DISPLAY INVISIBLE (-2125 3575);
FORCEPROP 1 LASTPIN (-2450 3550) $PN 1
J 0
(-2438 3562);
DISPLAY 0.787234 (-2438 3562);
PAINT MONO (-2438 3562);
FORCEPROP 1 LASTPIN (-2250 3550) $PN 2
J 0
(-2288 3562);
DISPLAY 0.787234 (-2288 3562);
PAINT MONO (-2288 3562);
FORCEPROP 1 LAST VALUE 0
J 2
(-2200 3550);
DISPLAY 0.404255 (-2200 3550);
FORCEPROP 1 LAST TOLERANCE 5%
J 0
(-2175 3550);
DISPLAY 0.404255 (-2175 3550);
FORCEPROP 0 LAST ROOM ADC_MAM_BOM2
J 0
(-2500 3625);
DISPLAY 0.680851 (-2500 3625);
PAINT RED (-2500 3625);
FORCEPROP 1 LAST PACK_TYPE 0402LF
J 0
(-2450 3450);
DISPLAY 0.404255 (-2450 3450);
FORCEPROP 1 LAST WATTAGE 1/16W
J 2
(-2225 3450);
DISPLAY 0.404255 (-2225 3450);
FORCEPROP 1 LAST MATERIAL EMPTY
J 0
(-2125 3550);
DISPLAY 0.404255 (-2125 3550);
PAINT RED (-2125 3550);
FORCEPROP 2 LAST CDS_LIB pure_quanta
J 0
(-2350 3550);
DISPLAY INVISIBLE (-2350 3550);
FORCEPROP 1 LAST PATH I138
J 0
(-2400 3700);
DISPLAY 0.978723 (-2400 3700);
PAINT WHITE (-2400 3700);
DISPLAY INVISIBLE (-2400 3700);
FORCEPROP 1 LAST PART_NUMBER CS00002JB13
J 0
(-2450 3425);
DISPLAY 0.404255 (-2450 3425);
DISPLAY INVISIBLE (-2450 3425);
FORCEADD Q_RES..1
(-2350 3500);
FORCEPROP 1 LAST LOCATION R1228
J 0
(-2550 3500);
DISPLAY 0.510638 (-2550 3500);
FORCEPROP 0 LAST $SEC 1
J 0
(-2125 3525);
DISPLAY 0.680851 (-2125 3525);
PAINT MONO (-2125 3525);
DISPLAY INVISIBLE (-2125 3525);
FORCEPROP 0 LAST CDS_SEC 1
J 0
(-2125 3525);
DISPLAY 1.021277 (-2125 3525);
DISPLAY INVISIBLE (-2125 3525);
FORCEPROP 1 LASTPIN (-2450 3500) $PN 1
J 0
(-2438 3512);
DISPLAY 0.787234 (-2438 3512);
PAINT MONO (-2438 3512);
FORCEPROP 1 LASTPIN (-2250 3500) $PN 2
J 0
(-2288 3512);
DISPLAY 0.787234 (-2288 3512);
PAINT MONO (-2288 3512);
FORCEPROP 1 LAST MATERIAL EMPTY
J 0
(-2125 3500);
DISPLAY 0.404255 (-2125 3500);
PAINT RED (-2125 3500);
FORCEPROP 1 LAST TOLERANCE 5%
J 0
(-2175 3500);
DISPLAY 0.404255 (-2175 3500);
FORCEPROP 1 LAST VALUE 0
J 2
(-2200 3500);
DISPLAY 0.404255 (-2200 3500);
FORCEPROP 0 LAST ROOM ADC_MAM_BOM2
J 0
(-2525 3375);
DISPLAY 0.680851 (-2525 3375);
PAINT RED (-2525 3375);
FORCEPROP 1 LAST WATTAGE 1/16W
J 2
(-2250 3425);
DISPLAY 0.319149 (-2250 3425);
DISPLAY INVISIBLE (-2250 3425);
FORCEPROP 1 LAST PACK_TYPE 0402LF
J 0
(-2100 3500);
DISPLAY 0.510638 (-2100 3500);
DISPLAY INVISIBLE (-2100 3500);
FORCEPROP 2 LAST CDS_LIB pure_quanta
J 0
(-2350 3500);
DISPLAY INVISIBLE (-2350 3500);
FORCEPROP 1 LAST PATH I139
J 0
(-2400 3650);
DISPLAY 0.978723 (-2400 3650);
PAINT WHITE (-2400 3650);
DISPLAY INVISIBLE (-2400 3650);
FORCEPROP 1 LAST PART_NUMBER CS00002JB13
J 0
(-2425 3450);
DISPLAY 0.319149 (-2425 3450);
DISPLAY INVISIBLE (-2425 3450);
FORCEADD UNIVERSAL_POWER..1
(-9025 6275);
FORCEPROP 3 LASTPIN (-9025 6225) SIG_NAME P5V_AUX\g
J 0
(-9015 6235);
DISPLAY 0.659574 (-9015 6235);
PAINT MONO (-9015 6235);
DISPLAY INVISIBLE (-9015 6235);
FORCEPROP 1 LAST HDL_POWER P5V_AUX
J 1
(-9025 6325);
DISPLAY 0.872340 (-9025 6325);
PAINT GREEN (-9025 6325);
FORCEPROP 2 LAST CDS_LIB pure_quanta_power
J 0
(-9025 6275);
DISPLAY INVISIBLE (-9025 6275);
FORCEPROP 1 LAST PATH I14
J 0
(-8975 6300);
DISPLAY 0.872340 (-8975 6300);
PAINT AQUA (-8975 6300);
DISPLAY INVISIBLE (-8975 6300);
FORCEADD Q_RES..1
(-1500 850);
FORCEPROP 1 LAST LOCATION R1244
J 0
(-1700 850);
DISPLAY 0.510638 (-1700 850);
FORCEPROP 0 LAST $SEC 1
J 0
(-1275 875);
DISPLAY 0.680851 (-1275 875);
PAINT MONO (-1275 875);
DISPLAY INVISIBLE (-1275 875);
FORCEPROP 0 LAST CDS_SEC 1
J 0
(-1275 875);
DISPLAY 1.021277 (-1275 875);
DISPLAY INVISIBLE (-1275 875);
FORCEPROP 1 LASTPIN (-1600 850) $PN 1
J 0
(-1588 862);
DISPLAY 0.787234 (-1588 862);
PAINT MONO (-1588 862);
FORCEPROP 1 LASTPIN (-1400 850) $PN 2
J 0
(-1438 862);
DISPLAY 0.787234 (-1438 862);
PAINT MONO (-1438 862);
FORCEPROP 0 LAST ROOM ADC_TI_BOM1
J 0
(-1675 725);
DISPLAY 0.680851 (-1675 725);
PAINT RED (-1675 725);
FORCEPROP 1 LAST MATERIAL CHIP
J 0
(-1275 850);
DISPLAY 0.404255 (-1275 850);
PAINT RED (-1275 850);
FORCEPROP 1 LAST TOLERANCE 5%
J 0
(-1325 850);
DISPLAY 0.404255 (-1325 850);
FORCEPROP 1 LAST VALUE 0
J 2
(-1350 850);
DISPLAY 0.404255 (-1350 850);
FORCEPROP 1 LAST WATTAGE 1/16W
J 2
(-1400 775);
DISPLAY 0.319149 (-1400 775);
DISPLAY INVISIBLE (-1400 775);
FORCEPROP 2 LAST CDS_LIB pure_quanta
J 0
(-1500 850);
DISPLAY INVISIBLE (-1500 850);
FORCEPROP 1 LAST PACK_TYPE 0402LF
J 0
(-1250 850);
DISPLAY 0.510638 (-1250 850);
DISPLAY INVISIBLE (-1250 850);
FORCEPROP 1 LAST PATH I140
J 0
(-1550 1000);
DISPLAY 0.978723 (-1550 1000);
PAINT WHITE (-1550 1000);
DISPLAY INVISIBLE (-1550 1000);
FORCEPROP 1 LAST PART_NUMBER CS00002JB13
J 0
(-1575 800);
DISPLAY 0.319149 (-1575 800);
DISPLAY INVISIBLE (-1575 800);
FORCEADD Q_RES..1
(-1500 900);
FORCEPROP 1 LAST LOCATION R1243
J 0
(-1700 900);
DISPLAY 0.510638 (-1700 900);
FORCEPROP 0 LAST $SEC 1
J 0
(-1275 925);
DISPLAY 0.680851 (-1275 925);
PAINT MONO (-1275 925);
DISPLAY INVISIBLE (-1275 925);
FORCEPROP 0 LAST CDS_SEC 1
J 0
(-1275 925);
DISPLAY 1.021277 (-1275 925);
DISPLAY INVISIBLE (-1275 925);
FORCEPROP 1 LASTPIN (-1600 900) $PN 1
J 0
(-1588 912);
DISPLAY 0.787234 (-1588 912);
PAINT MONO (-1588 912);
FORCEPROP 1 LASTPIN (-1400 900) $PN 2
J 0
(-1438 912);
DISPLAY 0.787234 (-1438 912);
PAINT MONO (-1438 912);
FORCEPROP 1 LAST PACK_TYPE 0402LF
J 0
(-1600 800);
DISPLAY 0.404255 (-1600 800);
FORCEPROP 1 LAST WATTAGE 1/16W
J 2
(-1375 800);
DISPLAY 0.404255 (-1375 800);
FORCEPROP 0 LAST ROOM ADC_TI_BOM1
J 0
(-1675 975);
DISPLAY 0.680851 (-1675 975);
PAINT RED (-1675 975);
FORCEPROP 1 LAST MATERIAL CHIP
J 0
(-1275 900);
DISPLAY 0.404255 (-1275 900);
PAINT RED (-1275 900);
FORCEPROP 1 LAST TOLERANCE 5%
J 0
(-1325 900);
DISPLAY 0.404255 (-1325 900);
FORCEPROP 1 LAST VALUE 0
J 2
(-1350 900);
DISPLAY 0.404255 (-1350 900);
FORCEPROP 2 LAST CDS_LIB pure_quanta
J 0
(-1500 900);
DISPLAY INVISIBLE (-1500 900);
FORCEPROP 1 LAST PATH I141
J 0
(-1550 1050);
DISPLAY 0.978723 (-1550 1050);
PAINT WHITE (-1550 1050);
DISPLAY INVISIBLE (-1550 1050);
FORCEPROP 1 LAST PART_NUMBER CS00002JB13
J 0
(-1600 775);
DISPLAY 0.404255 (-1600 775);
DISPLAY INVISIBLE (-1600 775);
FORCEADD ADC128D818CIMTXNOPB..1
(-1575 1950);
FORCEPROP 1 LAST LOCATION U51
J 0
(-1828 2603);
DISPLAY 0.723404 (-1828 2603);
PAINT GREEN (-1828 2603);
FORCEPROP 0 LAST $SEC 1
J 0
(-1825 2750);
DISPLAY 0.680851 (-1825 2750);
PAINT MONO (-1825 2750);
DISPLAY INVISIBLE (-1825 2750);
FORCEPROP 0 LAST CDS_SEC 1
J 0
(-1825 2750);
DISPLAY 1.021277 (-1825 2750);
DISPLAY INVISIBLE (-1825 2750);
FORCEPROP 0 LASTPIN (-1975 1975) $PN 7
J 2
(-1985 1985);
DISPLAY 0.680851 (-1985 1985);
PAINT MONO (-1985 1985);
FORCEPROP 0 LASTPIN (-1975 2025) $PN 8
J 2
(-1985 2035);
DISPLAY 0.680851 (-1985 2035);
PAINT MONO (-1985 2035);
FORCEPROP 0 LASTPIN (-1175 1525) $PN 4
J 0
(-1165 1535);
DISPLAY 0.680851 (-1165 1535);
PAINT MONO (-1165 1535);
FORCEPROP 0 LASTPIN (-1975 1525) $PN 16
J 2
(-1985 1535);
DISPLAY 0.680851 (-1985 1535);
PAINT MONO (-1985 1535);
FORCEPROP 0 LASTPIN (-1975 1575) $PN 15
J 2
(-1985 1585);
DISPLAY 0.680851 (-1985 1585);
PAINT MONO (-1985 1585);
FORCEPROP 0 LASTPIN (-1975 1625) $PN 14
J 2
(-1985 1635);
DISPLAY 0.680851 (-1985 1635);
PAINT MONO (-1985 1635);
FORCEPROP 0 LASTPIN (-1975 1675) $PN 13
J 2
(-1985 1685);
DISPLAY 0.680851 (-1985 1685);
PAINT MONO (-1985 1685);
FORCEPROP 0 LASTPIN (-1975 1725) $PN 12
J 2
(-1985 1735);
DISPLAY 0.680851 (-1985 1735);
PAINT MONO (-1985 1735);
FORCEPROP 0 LASTPIN (-1975 1775) $PN 11
J 2
(-1985 1785);
DISPLAY 0.680851 (-1985 1785);
PAINT MONO (-1985 1785);
FORCEPROP 0 LASTPIN (-1975 1825) $PN 10
J 2
(-1985 1835);
DISPLAY 0.680851 (-1985 1835);
PAINT MONO (-1985 1835);
FORCEPROP 0 LASTPIN (-1975 1875) $PN 9
J 2
(-1985 1885);
DISPLAY 0.680851 (-1985 1885);
PAINT MONO (-1985 1885);
FORCEPROP 0 LASTPIN (-1175 2375) $PN 6
J 0
(-1165 2385);
DISPLAY 0.680851 (-1165 2385);
PAINT MONO (-1165 2385);
FORCEPROP 0 LASTPIN (-1975 2275) $PN 3
J 2
(-1985 2285);
DISPLAY 0.680851 (-1985 2285);
PAINT MONO (-1985 2285);
FORCEPROP 0 LASTPIN (-1975 2225) $PN 2
J 2
(-1985 2235);
DISPLAY 0.680851 (-1985 2235);
PAINT MONO (-1985 2235);
FORCEPROP 0 LASTPIN (-1975 2375) $PN 5
J 2
(-1985 2385);
DISPLAY 0.680851 (-1985 2385);
PAINT MONO (-1985 2385);
FORCEPROP 0 LASTPIN (-1975 2125) $PN 1
J 2
(-1985 2135);
DISPLAY 0.680851 (-1985 2135);
PAINT MONO (-1985 2135);
FORCEPROP 2 LAST VALUE ADC128D818CIMTX/NOPB
J 0
(-1825 2650);
DISPLAY 1.021277 (-1825 2650);
FORCEPROP 2 LAST PART_TYPE SMLF
J 0
(-1825 2700);
DISPLAY 1.021277 (-1825 2700);
FORCEPROP 1 LAST MATERIAL IC
J 0
(-1828 2430);
DISPLAY 0.723404 (-1828 2430);
PAINT RED (-1828 2430);
FORCEPROP 0 LAST ROOM ADC_TI_BOM1
J 0
(-1825 2800);
DISPLAY 0.680851 (-1825 2800);
PAINT RED (-1825 2800);
FORCEPROP 2 LAST CDS_LIB pure_quanta
J 0
(-1575 1950);
DISPLAY INVISIBLE (-1575 1950);
FORCEPROP 1 LAST CDS_LMAN_SYM_OUTLINE -250,475,250,-475
J 0
(-1575 1950);
DISPLAY 0.468085 (-1575 1950);
PAINT GREEN (-1575 1950);
DISPLAY INVISIBLE (-1575 1950);
FORCEPROP 1 LAST PIN_NAMES_ROTATE True
J 0
(-1575 1950);
DISPLAY 0.489362 (-1575 1950);
PAINT GREEN (-1575 1950);
DISPLAY INVISIBLE (-1575 1950);
FORCEPROP 1 LAST PATH I142
J 0
(-1575 1950);
DISPLAY 0.723404 (-1575 1950);
PAINT GREEN (-1575 1950);
DISPLAY INVISIBLE (-1575 1950);
FORCEPROP 1 LAST PART_NUMBER AL000128K00
J 0
(-1828 2519);
DISPLAY 0.723404 (-1828 2519);
PAINT GREEN (-1828 2519);
DISPLAY INVISIBLE (-1828 2519);
FORCEADD UNIVERSAL_GND..1
(-1000 1325);
FORCEPROP 3 LASTPIN (-1000 1375) SIG_NAME GND\g
J 0
(-990 1385);
DISPLAY 0.659574 (-990 1385);
PAINT MONO (-990 1385);
DISPLAY INVISIBLE (-990 1385);
FORCEPROP 2 LAST CDS_LIB pure_quanta_power
J 0
(-1000 1325);
DISPLAY INVISIBLE (-1000 1325);
FORCEPROP 1 LAST HDL_POWER GND
J 1
(-975 1250);
DISPLAY 0.872340 (-975 1250);
PAINT GREEN (-975 1250);
DISPLAY INVISIBLE (-975 1250);
FORCEPROP 1 LAST PATH I143
J 0
(-925 1325);
DISPLAY 0.872340 (-925 1325);
PAINT AQUA (-925 1325);
DISPLAY INVISIBLE (-925 1325);
FORCEADD OFFPAGE..2
(-450 850);
FORCEPROP 2 LAST $XR0 259 
J 0
(-231 850);
DISPLAY 0.638298 (-231 850);
PAINT MONO (-231 850);
FORCEPROP 2 LAST CDS_LIB standard
J 0
(-450 850);
DISPLAY INVISIBLE (-450 850);
FORCEPROP 1 LAST OFFPAGE TRUE
J 0
(-125 725);
DISPLAY 0.872340 (-125 725);
DISPLAY INVISIBLE (-125 725);
FORCEPROP 1 LAST COMMENT_BODY TRUE
J 0
(-495 755);
DISPLAY 0.872340 (-495 755);
PAINT GREEN (-495 755);
DISPLAY INVISIBLE (-495 755);
FORCEPROP 2 LAST PATH I144
J 0
(-250 900);
DISPLAY 0.680851 (-250 900);
DISPLAY INVISIBLE (-250 900);
FORCEADD OFFPAGE..3
(-450 900);
FORCEPROP 2 LAST $XR0 259 
J 0
(-236 900);
DISPLAY 0.638298 (-236 900);
PAINT MONO (-236 900);
FORCEPROP 2 LAST CDS_LIB standard
J 0
(-450 900);
DISPLAY INVISIBLE (-450 900);
FORCEPROP 1 LAST OFFPAGE TRUE
J 0
(-125 775);
DISPLAY 0.872340 (-125 775);
PAINT GREEN (-125 775);
DISPLAY INVISIBLE (-125 775);
FORCEPROP 1 LAST COMMENT_BODY TRUE
J 0
(-500 800);
DISPLAY 0.872340 (-500 800);
PAINT GREEN (-500 800);
DISPLAY INVISIBLE (-500 800);
FORCEPROP 2 LAST PATH I145
J 0
(-225 950);
DISPLAY 0.680851 (-225 950);
DISPLAY INVISIBLE (-225 950);
FORCEADD OFFPAGE..2
(-1300 3500);
FORCEPROP 2 LAST $XR0 259 
J 0
(-1111 3500);
DISPLAY 0.638298 (-1111 3500);
PAINT MONO (-1111 3500);
FORCEPROP 2 LAST CDS_LIB standard
J 0
(-1300 3500);
DISPLAY INVISIBLE (-1300 3500);
FORCEPROP 1 LAST OFFPAGE TRUE
J 0
(-975 3375);
DISPLAY 0.872340 (-975 3375);
DISPLAY INVISIBLE (-975 3375);
FORCEPROP 1 LAST COMMENT_BODY TRUE
J 0
(-1345 3405);
DISPLAY 0.872340 (-1345 3405);
PAINT GREEN (-1345 3405);
DISPLAY INVISIBLE (-1345 3405);
FORCEPROP 2 LAST PATH I146
J 0
(-1075 3550);
DISPLAY 0.680851 (-1075 3550);
DISPLAY INVISIBLE (-1075 3550);
FORCEADD OFFPAGE..3
(-1300 3550);
FORCEPROP 2 LAST $XR0 259 
J 0
(-1086 3550);
DISPLAY 0.638298 (-1086 3550);
PAINT MONO (-1086 3550);
FORCEPROP 2 LAST CDS_LIB standard
J 0
(-1300 3550);
DISPLAY INVISIBLE (-1300 3550);
FORCEPROP 1 LAST OFFPAGE TRUE
J 0
(-975 3425);
DISPLAY 0.872340 (-975 3425);
PAINT GREEN (-975 3425);
DISPLAY INVISIBLE (-975 3425);
FORCEPROP 1 LAST COMMENT_BODY TRUE
J 0
(-1350 3450);
DISPLAY 0.872340 (-1350 3450);
PAINT GREEN (-1350 3450);
DISPLAY INVISIBLE (-1350 3450);
FORCEPROP 2 LAST PATH I147
J 0
(-1075 3600);
DISPLAY 0.680851 (-1075 3600);
DISPLAY INVISIBLE (-1075 3600);
FORCEADD OFFPAGE..4
R 2
(-3625 4400);
FORCEPROP 2 LAST $XR0 259 
J 0
(-3877 4400);
DISPLAY 0.638298 (-3877 4400);
PAINT MONO (-3877 4400);
FORCEPROP 2 LAST CDS_LIB standard
J 0
(-3625 4400);
DISPLAY INVISIBLE (-3625 4400);
FORCEPROP 1 LAST OFFPAGE TRUE
J 2
(-3950 4275);
DISPLAY 0.872340 (-3950 4275);
DISPLAY INVISIBLE (-3950 4275);
FORCEPROP 1 LAST COMMENT_BODY TRUE
J 2
(-3600 4300);
DISPLAY 0.872340 (-3600 4300);
PAINT GREEN (-3600 4300);
DISPLAY INVISIBLE (-3600 4300);
FORCEPROP 2 LAST PATH I148
J 0
(-3875 4450);
DISPLAY 0.680851 (-3875 4450);
DISPLAY INVISIBLE (-3875 4450);
FORCEADD OFFPAGE..4
R 2
(-3625 4600);
FORCEPROP 2 LAST $XR0 259 
J 0
(-3877 4600);
DISPLAY 0.638298 (-3877 4600);
PAINT MONO (-3877 4600);
FORCEPROP 2 LAST CDS_LIB standard
J 0
(-3625 4600);
DISPLAY INVISIBLE (-3625 4600);
FORCEPROP 1 LAST OFFPAGE TRUE
J 2
(-3950 4475);
DISPLAY 0.872340 (-3950 4475);
DISPLAY INVISIBLE (-3950 4475);
FORCEPROP 1 LAST COMMENT_BODY TRUE
J 2
(-3600 4500);
DISPLAY 0.872340 (-3600 4500);
PAINT GREEN (-3600 4500);
DISPLAY INVISIBLE (-3600 4500);
FORCEPROP 2 LAST PATH I149
J 0
(-3875 4650);
DISPLAY 0.680851 (-3875 4650);
DISPLAY INVISIBLE (-3875 4650);
FORCEADD Q_RES..1
(-8400 5625);
FORCEPROP 1 LAST LOCATION R1263
J 0
(-8575 5625);
DISPLAY 0.510638 (-8575 5625);
FORCEPROP 0 LAST $SEC 1
J 0
(-8525 5675);
DISPLAY 0.680851 (-8525 5675);
PAINT MONO (-8525 5675);
DISPLAY INVISIBLE (-8525 5675);
FORCEPROP 0 LAST CDS_SEC 1
J 0
(-8525 5675);
DISPLAY 1.021277 (-8525 5675);
DISPLAY INVISIBLE (-8525 5675);
FORCEPROP 1 LASTPIN (-8500 5625) $PN 1
J 0
(-8488 5637);
DISPLAY 0.787234 (-8488 5637);
PAINT MONO (-8488 5637);
FORCEPROP 1 LASTPIN (-8300 5625) $PN 2
J 0
(-8338 5637);
DISPLAY 0.787234 (-8338 5637);
PAINT MONO (-8338 5637);
FORCEPROP 0 LAST ROOM ADC_TI_BOM1
J 0
(-8525 5550);
DISPLAY 0.680851 (-8525 5550);
PAINT RED (-8525 5550);
FORCEPROP 1 LAST TOLERANCE 5%
J 0
(-8225 5625);
DISPLAY 0.404255 (-8225 5625);
FORCEPROP 1 LAST MATERIAL CHIP
J 0
(-8175 5625);
DISPLAY 0.404255 (-8175 5625);
PAINT RED (-8175 5625);
FORCEPROP 1 LAST VALUE 0
J 2
(-8250 5625);
DISPLAY 0.404255 (-8250 5625);
FORCEPROP 2 LAST CDS_LIB pure_quanta
J 0
(-8400 5625);
DISPLAY INVISIBLE (-8400 5625);
FORCEPROP 1 LAST WATTAGE 1/16W
J 2
(-8300 5550);
DISPLAY 0.319149 (-8300 5550);
DISPLAY INVISIBLE (-8300 5550);
FORCEPROP 1 LAST PACK_TYPE 0402LF
J 0
(-8150 5625);
DISPLAY 0.510638 (-8150 5625);
DISPLAY INVISIBLE (-8150 5625);
FORCEPROP 1 LAST PATH I15
J 0
(-8450 5775);
DISPLAY 0.978723 (-8450 5775);
PAINT WHITE (-8450 5775);
DISPLAY INVISIBLE (-8450 5775);
FORCEPROP 1 LAST PART_NUMBER CS00002JB13
J 0
(-8475 5575);
DISPLAY 0.319149 (-8475 5575);
DISPLAY INVISIBLE (-8475 5575);
FORCEADD OFFPAGE..4
R 2
(-3625 4500);
FORCEPROP 2 LAST $XR0 259 
J 0
(-3877 4500);
DISPLAY 0.638298 (-3877 4500);
PAINT MONO (-3877 4500);
FORCEPROP 2 LAST CDS_LIB standard
J 0
(-3625 4500);
DISPLAY INVISIBLE (-3625 4500);
FORCEPROP 1 LAST OFFPAGE TRUE
J 2
(-3950 4375);
DISPLAY 0.872340 (-3950 4375);
DISPLAY INVISIBLE (-3950 4375);
FORCEPROP 1 LAST COMMENT_BODY TRUE
J 2
(-3600 4400);
DISPLAY 0.872340 (-3600 4400);
PAINT GREEN (-3600 4400);
DISPLAY INVISIBLE (-3600 4400);
FORCEPROP 2 LAST PATH I150
J 0
(-3875 4550);
DISPLAY 0.680851 (-3875 4550);
DISPLAY INVISIBLE (-3875 4550);
FORCEADD OFFPAGE..4
R 2
(-3625 4700);
FORCEPROP 2 LAST $XR0 259 
J 0
(-3877 4700);
DISPLAY 0.638298 (-3877 4700);
PAINT MONO (-3877 4700);
FORCEPROP 2 LAST CDS_LIB standard
J 0
(-3625 4700);
DISPLAY INVISIBLE (-3625 4700);
FORCEPROP 1 LAST OFFPAGE TRUE
J 2
(-3950 4575);
DISPLAY 0.872340 (-3950 4575);
DISPLAY INVISIBLE (-3950 4575);
FORCEPROP 1 LAST COMMENT_BODY TRUE
J 2
(-3600 4600);
DISPLAY 0.872340 (-3600 4600);
PAINT GREEN (-3600 4600);
DISPLAY INVISIBLE (-3600 4600);
FORCEPROP 2 LAST PATH I151
J 0
(-3875 4750);
DISPLAY 0.680851 (-3875 4750);
DISPLAY INVISIBLE (-3875 4750);
FORCEADD Q_CAP..1
(-3775 5200);
FORCEPROP 1 LAST LOCATION C1076
J 0
(-3725 5300);
DISPLAY 0.510638 (-3725 5300);
FORCEPROP 2 LAST $SEC 1
J 0
(-3725 5400);
DISPLAY 0.680851 (-3725 5400);
PAINT MONO (-3725 5400);
DISPLAY INVISIBLE (-3725 5400);
FORCEPROP 2 LAST CDS_SEC 1
J 0
(-3725 5400);
DISPLAY 1.021277 (-3725 5400);
DISPLAY INVISIBLE (-3725 5400);
FORCEPROP 1 LASTPIN (-3775 5300) $PN 1
J 0
(-3765 5280);
DISPLAY 0.787234 (-3765 5280);
FORCEPROP 1 LASTPIN (-3775 5100) $PN 2
J 0
(-3765 5080);
DISPLAY 0.787234 (-3765 5080);
FORCEPROP 1 LAST VALUE 10UF
J 0
(-3725 5250);
DISPLAY 0.510638 (-3725 5250);
FORCEPROP 1 LAST VOLTAGE 16V
J 0
(-3725 5200);
DISPLAY 0.510638 (-3725 5200);
FORCEPROP 1 LAST PACK_TYPE C0805
J 0
(-3725 5000);
DISPLAY 0.510638 (-3725 5000);
FORCEPROP 1 LAST TOLERANCE 10%
J 0
(-3725 5150);
DISPLAY 0.510638 (-3725 5150);
FORCEPROP 1 LAST MATERIAL X6S
J 0
(-3725 5100);
DISPLAY 0.510638 (-3725 5100);
FORCEPROP 2 LAST CDS_LIB pure_quanta
J 0
(-3775 5200);
PAINT MONO (-3775 5200);
DISPLAY INVISIBLE (-3775 5200);
FORCEPROP 1 LAST PATH I152
J 0
(-3725 5350);
DISPLAY 0.978723 (-3725 5350);
PAINT WHITE (-3725 5350);
DISPLAY INVISIBLE (-3725 5350);
FORCEPROP 1 LAST PART_NUMBER CH6103KEA00
J 0
(-3725 5050);
DISPLAY 0.510638 (-3725 5050);
DISPLAY INVISIBLE (-3725 5050);
FORCEADD UNIVERSAL_GND..1
(-3775 5000);
FORCEPROP 3 LASTPIN (-3775 5050) SIG_NAME GND\g
J 0
(-3765 5060);
DISPLAY 0.659574 (-3765 5060);
PAINT MONO (-3765 5060);
DISPLAY INVISIBLE (-3765 5060);
FORCEPROP 2 LAST CDS_LIB pure_quanta_power
J 0
(-3775 5000);
DISPLAY INVISIBLE (-3775 5000);
FORCEPROP 1 LAST HDL_POWER GND
J 1
(-3750 4925);
DISPLAY 0.872340 (-3750 4925);
PAINT GREEN (-3750 4925);
DISPLAY INVISIBLE (-3750 4925);
FORCEPROP 1 LAST PATH I153
J 0
(-3700 5000);
DISPLAY 0.872340 (-3700 5000);
PAINT AQUA (-3700 5000);
DISPLAY INVISIBLE (-3700 5000);
FORCEADD Q_RES..1
(-3425 5375);
FORCEPROP 1 LAST LOCATION R1230
J 0
(-3675 5375);
DISPLAY 0.638298 (-3675 5375);
FORCEPROP 2 LAST $SEC 1
J 0
(-3225 5575);
DISPLAY 0.680851 (-3225 5575);
PAINT MONO (-3225 5575);
DISPLAY INVISIBLE (-3225 5575);
FORCEPROP 2 LAST CDS_SEC 1
J 0
(-3225 5575);
DISPLAY 1.021277 (-3225 5575);
DISPLAY INVISIBLE (-3225 5575);
FORCEPROP 1 LASTPIN (-3525 5375) $PN 1
J 0
(-3513 5387);
DISPLAY 0.787234 (-3513 5387);
FORCEPROP 1 LASTPIN (-3325 5375) $PN 2
J 0
(-3363 5387);
DISPLAY 0.787234 (-3363 5387);
FORCEPROP 1 LAST VALUE 2K
J 2
(-3250 5375);
DISPLAY 0.638298 (-3250 5375);
FORCEPROP 1 LAST TOLERANCE 1%
J 0
(-3225 5375);
DISPLAY 0.638298 (-3225 5375);
FORCEPROP 1 LAST MATERIAL CHIP
J 0
(-3150 5375);
DISPLAY 0.638298 (-3150 5375);
FORCEPROP 1 LAST PACK_TYPE 0402LF
J 0
(-3600 5525);
DISPLAY 0.638298 (-3600 5525);
FORCEPROP 1 LAST WATTAGE 1/16W
J 2
(-3225 5525);
DISPLAY 0.638298 (-3225 5525);
FORCEPROP 2 LAST CDS_LIB pure_quanta
J 0
(-3425 5375);
PAINT MONO (-3425 5375);
DISPLAY INVISIBLE (-3425 5375);
FORCEPROP 1 LAST PATH I154
J 0
(-3475 5525);
DISPLAY 0.978723 (-3475 5525);
PAINT WHITE (-3475 5525);
DISPLAY INVISIBLE (-3475 5525);
FORCEPROP 1 LAST PART_NUMBER CS22002FB07
J 0
(-3600 5475);
DISPLAY 0.638298 (-3600 5475);
DISPLAY INVISIBLE (-3600 5475);
FORCEADD UNIVERSAL_GND..1
(-2875 4100);
FORCEPROP 3 LASTPIN (-2875 4150) SIG_NAME GND\g
J 0
(-2865 4160);
DISPLAY 0.659574 (-2865 4160);
PAINT MONO (-2865 4160);
DISPLAY INVISIBLE (-2865 4160);
FORCEPROP 2 LAST CDS_LIB pure_quanta_power
J 0
(-2875 4100);
DISPLAY INVISIBLE (-2875 4100);
FORCEPROP 1 LAST HDL_POWER GND
J 1
(-2850 4025);
DISPLAY 0.872340 (-2850 4025);
PAINT GREEN (-2850 4025);
DISPLAY INVISIBLE (-2850 4025);
FORCEPROP 1 LAST PATH I155
J 0
(-2800 4100);
DISPLAY 0.872340 (-2800 4100);
PAINT AQUA (-2800 4100);
DISPLAY INVISIBLE (-2800 4100);
FORCEADD MAX11617EEET..1
(-2375 4750);
FORCEPROP 1 LAST LOCATION U50
J 0
(-2620 5431);
DISPLAY 0.723404 (-2620 5431);
PAINT GREEN (-2620 5431);
FORCEPROP 2 LAST SEC 1
J 0
(-2600 5575);
DISPLAY 0.680851 (-2600 5575);
PAINT MONO (-2600 5575);
DISPLAY INVISIBLE (-2600 5575);
FORCEPROP 2 LASTPIN (-2775 4700) $PN 5
J 2
(-2785 4710);
DISPLAY 0.680851 (-2785 4710);
PAINT MONO (-2785 4710);
FORCEPROP 2 LASTPIN (-2775 4600) $PN 6
J 2
(-2785 4610);
DISPLAY 0.680851 (-2785 4610);
PAINT MONO (-2785 4610);
FORCEPROP 2 LASTPIN (-2775 4500) $PN 7
J 2
(-2785 4510);
DISPLAY 0.680851 (-2785 4510);
PAINT MONO (-2785 4510);
FORCEPROP 2 LASTPIN (-2775 4400) $PN 8
J 2
(-2785 4410);
DISPLAY 0.680851 (-2785 4410);
PAINT MONO (-2785 4410);
FORCEPROP 2 LASTPIN (-1975 4400) $PN 9
J 0
(-1965 4410);
DISPLAY 0.680851 (-1965 4410);
PAINT MONO (-1965 4410);
FORCEPROP 2 LASTPIN (-1975 4500) $PN 10
J 0
(-1965 4510);
DISPLAY 0.680851 (-1965 4510);
PAINT MONO (-1965 4510);
FORCEPROP 2 LASTPIN (-1975 4600) $PN 11
J 0
(-1965 4610);
DISPLAY 0.680851 (-1965 4610);
PAINT MONO (-1965 4610);
FORCEPROP 2 LASTPIN (-1975 4700) $PN 12
J 0
(-1965 4710);
DISPLAY 0.680851 (-1965 4710);
PAINT MONO (-1965 4710);
FORCEPROP 2 LASTPIN (-2775 4800) $PN 4
J 2
(-2785 4810);
DISPLAY 0.680851 (-2785 4810);
PAINT MONO (-2785 4810);
FORCEPROP 2 LASTPIN (-2775 4900) $PN 3
J 2
(-2785 4910);
DISPLAY 0.680851 (-2785 4910);
PAINT MONO (-2785 4910);
FORCEPROP 2 LASTPIN (-2775 5000) $PN 2
J 2
(-2785 5010);
DISPLAY 0.680851 (-2785 5010);
PAINT MONO (-2785 5010);
FORCEPROP 2 LASTPIN (-2775 5100) $PN 1
J 2
(-2785 5110);
DISPLAY 0.680851 (-2785 5110);
PAINT MONO (-2785 5110);
FORCEPROP 2 LASTPIN (-1975 5000) $PN 15
J 0
(-1965 5010);
DISPLAY 0.680851 (-1965 5010);
PAINT MONO (-1965 5010);
FORCEPROP 2 LASTPIN (-1975 4800) $PN 13
J 0
(-1965 4810);
DISPLAY 0.680851 (-1965 4810);
PAINT MONO (-1965 4810);
FORCEPROP 2 LASTPIN (-1975 4900) $PN 14
J 0
(-1965 4910);
DISPLAY 0.680851 (-1965 4910);
PAINT MONO (-1965 4910);
FORCEPROP 2 LASTPIN (-1975 5100) $PN 16
J 0
(-1965 5110);
DISPLAY 0.680851 (-1965 5110);
PAINT MONO (-1965 5110);
FORCEPROP 0 LAST ROOM ADC_MAM_BOM2
J 0
(-2600 5625);
DISPLAY 0.680851 (-2600 5625);
PAINT RED (-2600 5625);
FORCEPROP 2 LAST PART_TYPE SMLF
J 0
(-2600 5525);
DISPLAY 1.021277 (-2600 5525);
FORCEPROP 1 LAST MATERIAL EMPTY
J 0
(-2620 5157);
DISPLAY 0.723404 (-2620 5157);
PAINT GREEN (-2620 5157);
FORCEPROP 2 LAST VALUE MAX11617EEE+T
J 0
(-2600 5475);
DISPLAY 1.021277 (-2600 5475);
FORCEPROP 2 LAST CDS_LIB pure_quanta
J 0
(-2375 4750);
DISPLAY INVISIBLE (-2375 4750);
FORCEPROP 1 LAST NEEDS_NO_SIZE TRUE
J 0
(-2375 4750);
DISPLAY 0.723404 (-2375 4750);
PAINT GREEN (-2375 4750);
DISPLAY INVISIBLE (-2375 4750);
FORCEPROP 1 LAST CDS_LMAN_SYM_OUTLINE -250,400,250,-400
J 0
(-2375 4750);
DISPLAY 0.468085 (-2375 4750);
PAINT GREEN (-2375 4750);
DISPLAY INVISIBLE (-2375 4750);
FORCEPROP 2 LAST SEC_TYPE 
J 0
(-2600 5575);
DISPLAY 1.021277 (-2600 5575);
DISPLAY INVISIBLE (-2600 5575);
FORCEPROP 1 LAST PATH I156
J 0
(-2375 4750);
DISPLAY 0.723404 (-2375 4750);
PAINT GREEN (-2375 4750);
DISPLAY INVISIBLE (-2375 4750);
FORCEPROP 1 LAST PART_NUMBER AL011617W00
J 0
(-2620 5284);
DISPLAY 0.723404 (-2620 5284);
PAINT GREEN (-2620 5284);
DISPLAY INVISIBLE (-2620 5284);
FORCEADD UNIVERSAL_GND..1
(-1850 4150);
FORCEPROP 3 LASTPIN (-1850 4200) SIG_NAME GND\g
J 0
(-1840 4210);
DISPLAY 0.659574 (-1840 4210);
PAINT MONO (-1840 4210);
DISPLAY INVISIBLE (-1840 4210);
FORCEPROP 2 LAST CDS_LIB pure_quanta_power
J 0
(-1850 4150);
DISPLAY INVISIBLE (-1850 4150);
FORCEPROP 1 LAST HDL_POWER GND
J 1
(-1825 4075);
DISPLAY 0.872340 (-1825 4075);
PAINT GREEN (-1825 4075);
DISPLAY INVISIBLE (-1825 4075);
FORCEPROP 1 LAST PATH I157
J 0
(-1775 4150);
DISPLAY 0.872340 (-1775 4150);
PAINT AQUA (-1775 4150);
DISPLAY INVISIBLE (-1775 4150);
FORCEADD OFFPAGE..4
(-1125 4400);
FORCEPROP 2 LAST $XR0 259 
J 0
(-939 4400);
DISPLAY 0.638298 (-939 4400);
PAINT MONO (-939 4400);
FORCEPROP 2 LAST CDS_LIB standard
J 2
(-1125 4400);
DISPLAY INVISIBLE (-1125 4400);
FORCEPROP 1 LAST OFFPAGE TRUE
J 0
(-800 4275);
DISPLAY 0.872340 (-800 4275);
DISPLAY INVISIBLE (-800 4275);
FORCEPROP 1 LAST COMMENT_BODY TRUE
J 0
(-1150 4300);
DISPLAY 0.872340 (-1150 4300);
PAINT GREEN (-1150 4300);
DISPLAY INVISIBLE (-1150 4300);
FORCEPROP 2 LAST PATH I158
J 0
(-925 4450);
DISPLAY 0.680851 (-925 4450);
DISPLAY INVISIBLE (-925 4450);
FORCEADD OFFPAGE..1
R 2
(-1100 4700);
FORCEPROP 2 LAST $XR0 259 
J 0
(-914 4700);
DISPLAY 0.638298 (-914 4700);
PAINT MONO (-914 4700);
FORCEPROP 2 LAST CDS_LIB standard
J 2
(-1100 4700);
DISPLAY INVISIBLE (-1100 4700);
FORCEPROP 1 LAST OFFPAGE TRUE
J 2
(-1425 4575);
DISPLAY 0.872340 (-1425 4575);
PAINT GREEN (-1425 4575);
DISPLAY INVISIBLE (-1425 4575);
FORCEPROP 1 LAST COMMENT_BODY TRUE
J 2
(-1225 4600);
DISPLAY 0.872340 (-1225 4600);
PAINT GREEN (-1225 4600);
DISPLAY INVISIBLE (-1225 4600);
FORCEPROP 2 LAST PATH I159
J 0
(-900 4750);
DISPLAY 0.680851 (-900 4750);
DISPLAY INVISIBLE (-900 4750);
FORCEADD Q_RES..1
(-8400 5775);
FORCEPROP 1 LAST LOCATION R1260
J 0
(-8575 5775);
DISPLAY 0.510638 (-8575 5775);
FORCEPROP 0 LAST $SEC 1
J 0
(-8525 5825);
DISPLAY 0.680851 (-8525 5825);
PAINT MONO (-8525 5825);
DISPLAY INVISIBLE (-8525 5825);
FORCEPROP 0 LAST CDS_SEC 1
J 0
(-8525 5825);
DISPLAY 1.021277 (-8525 5825);
DISPLAY INVISIBLE (-8525 5825);
FORCEPROP 1 LASTPIN (-8500 5775) $PN 1
J 0
(-8488 5787);
DISPLAY 0.787234 (-8488 5787);
PAINT MONO (-8488 5787);
FORCEPROP 1 LASTPIN (-8300 5775) $PN 2
J 0
(-8338 5787);
DISPLAY 0.787234 (-8338 5787);
PAINT MONO (-8338 5787);
FORCEPROP 0 LAST ROOM ADC_MAM_BOM2
J 0
(-8525 5850);
DISPLAY 0.680851 (-8525 5850);
PAINT RED (-8525 5850);
FORCEPROP 1 LAST MATERIAL EMPTY
J 0
(-8175 5775);
DISPLAY 0.404255 (-8175 5775);
FORCEPROP 1 LAST VALUE 0
J 2
(-8250 5775);
DISPLAY 0.404255 (-8250 5775);
FORCEPROP 1 LAST TOLERANCE 5%
J 0
(-8225 5775);
DISPLAY 0.404255 (-8225 5775);
FORCEPROP 1 LAST PACK_TYPE 0402LF
J 0
(-8150 5775);
DISPLAY 0.510638 (-8150 5775);
DISPLAY INVISIBLE (-8150 5775);
FORCEPROP 1 LAST WATTAGE 1/16W
J 2
(-8300 5700);
DISPLAY 0.319149 (-8300 5700);
DISPLAY INVISIBLE (-8300 5700);
FORCEPROP 2 LAST CDS_LIB pure_quanta
J 0
(-8400 5775);
DISPLAY INVISIBLE (-8400 5775);
FORCEPROP 1 LAST PATH I16
J 0
(-8450 5925);
DISPLAY 0.978723 (-8450 5925);
PAINT WHITE (-8450 5925);
DISPLAY INVISIBLE (-8450 5925);
FORCEPROP 1 LAST PART_NUMBER CS00002JB13
J 0
(-8475 5725);
DISPLAY 0.319149 (-8475 5725);
DISPLAY INVISIBLE (-8475 5725);
FORCEADD OFFPAGE..1
R 2
(-1100 4600);
FORCEPROP 2 LAST $XR0 259 
J 0
(-914 4600);
DISPLAY 0.638298 (-914 4600);
PAINT MONO (-914 4600);
FORCEPROP 2 LAST CDS_LIB standard
J 2
(-1100 4600);
DISPLAY INVISIBLE (-1100 4600);
FORCEPROP 1 LAST OFFPAGE TRUE
J 2
(-1425 4475);
DISPLAY 0.872340 (-1425 4475);
PAINT GREEN (-1425 4475);
DISPLAY INVISIBLE (-1425 4475);
FORCEPROP 1 LAST COMMENT_BODY TRUE
J 2
(-1225 4500);
DISPLAY 0.872340 (-1225 4500);
PAINT GREEN (-1225 4500);
DISPLAY INVISIBLE (-1225 4500);
FORCEPROP 2 LAST PATH I160
J 0
(-900 4650);
DISPLAY 0.680851 (-900 4650);
DISPLAY INVISIBLE (-900 4650);
FORCEADD OFFPAGE..4
(-1125 4500);
FORCEPROP 2 LAST $XR0 259 
J 0
(-939 4500);
DISPLAY 0.638298 (-939 4500);
PAINT MONO (-939 4500);
FORCEPROP 2 LAST CDS_LIB standard
J 2
(-1125 4500);
DISPLAY INVISIBLE (-1125 4500);
FORCEPROP 1 LAST OFFPAGE TRUE
J 0
(-800 4375);
DISPLAY 0.872340 (-800 4375);
DISPLAY INVISIBLE (-800 4375);
FORCEPROP 1 LAST COMMENT_BODY TRUE
J 0
(-1150 4400);
DISPLAY 0.872340 (-1150 4400);
PAINT GREEN (-1150 4400);
DISPLAY INVISIBLE (-1150 4400);
FORCEPROP 2 LAST PATH I161
J 0
(-925 4550);
DISPLAY 0.680851 (-925 4550);
DISPLAY INVISIBLE (-925 4550);
FORCEADD OFFPAGE..1
R 2
(-1000 4800);
FORCEPROP 2 LAST $XR0 259 
J 0
(-814 4800);
DISPLAY 0.638298 (-814 4800);
PAINT MONO (-814 4800);
FORCEPROP 2 LAST CDS_LIB standard
J 2
(-1000 4800);
DISPLAY INVISIBLE (-1000 4800);
FORCEPROP 1 LAST OFFPAGE TRUE
J 2
(-1325 4675);
DISPLAY 0.872340 (-1325 4675);
PAINT GREEN (-1325 4675);
DISPLAY INVISIBLE (-1325 4675);
FORCEPROP 1 LAST COMMENT_BODY TRUE
J 2
(-1125 4700);
DISPLAY 0.872340 (-1125 4700);
PAINT GREEN (-1125 4700);
DISPLAY INVISIBLE (-1125 4700);
FORCEPROP 2 LAST PATH I162
J 0
(-800 4850);
DISPLAY 0.680851 (-800 4850);
DISPLAY INVISIBLE (-800 4850);
FORCEADD OFFPAGE..1
R 2
(-1000 4900);
FORCEPROP 2 LAST $XR0 259 
J 0
(-814 4900);
DISPLAY 0.638298 (-814 4900);
PAINT MONO (-814 4900);
FORCEPROP 2 LAST CDS_LIB standard
J 0
(-1000 4900);
DISPLAY INVISIBLE (-1000 4900);
FORCEPROP 1 LAST OFFPAGE TRUE
J 2
(-1325 4775);
DISPLAY 0.872340 (-1325 4775);
PAINT GREEN (-1325 4775);
DISPLAY INVISIBLE (-1325 4775);
FORCEPROP 1 LAST COMMENT_BODY TRUE
J 2
(-1125 4800);
DISPLAY 0.872340 (-1125 4800);
PAINT GREEN (-1125 4800);
DISPLAY INVISIBLE (-1125 4800);
FORCEPROP 2 LAST PATH I163
J 0
(-800 4950);
DISPLAY 0.680851 (-800 4950);
DISPLAY INVISIBLE (-800 4950);
FORCEADD UNIVERSAL_GND..1
(-1450 5000);
FORCEPROP 3 LASTPIN (-1450 5050) SIG_NAME GND\g
J 0
(-1440 5060);
DISPLAY 0.659574 (-1440 5060);
PAINT MONO (-1440 5060);
DISPLAY INVISIBLE (-1440 5060);
FORCEPROP 2 LAST CDS_LIB pure_quanta_power
J 0
(-1450 5000);
DISPLAY INVISIBLE (-1450 5000);
FORCEPROP 1 LAST HDL_POWER GND
J 1
(-1425 4925);
DISPLAY 0.872340 (-1425 4925);
PAINT GREEN (-1425 4925);
DISPLAY INVISIBLE (-1425 4925);
FORCEPROP 1 LAST PATH I164
J 0
(-1375 5000);
DISPLAY 0.872340 (-1375 5000);
PAINT AQUA (-1375 5000);
DISPLAY INVISIBLE (-1375 5000);
FORCEADD Q_CAP..1
R 2
(-1450 5175);
FORCEPROP 1 LAST LOCATION C1075
J 2
(-1275 5300);
DISPLAY 0.638298 (-1275 5300);
FORCEPROP 0 LAST $SEC 1
J 0
(-1500 5325);
DISPLAY 0.680851 (-1500 5325);
PAINT MONO (-1500 5325);
DISPLAY INVISIBLE (-1500 5325);
FORCEPROP 0 LAST CDS_SEC 1
J 0
(-1500 5325);
DISPLAY 1.021277 (-1500 5325);
DISPLAY INVISIBLE (-1500 5325);
FORCEPROP 1 LASTPIN (-1450 5275) $PN 1
J 2
(-1460 5255);
DISPLAY 0.787234 (-1460 5255);
PAINT MONO (-1460 5255);
FORCEPROP 1 LASTPIN (-1450 5075) $PN 2
J 2
(-1460 5055);
DISPLAY 0.787234 (-1460 5055);
PAINT MONO (-1460 5055);
FORCEPROP 1 LAST PACK_TYPE 0402
J 2
(-1275 5000);
DISPLAY 0.510638 (-1275 5000);
FORCEPROP 1 LAST VALUE 0.1UF
J 2
(-1275 5250);
DISPLAY 0.510638 (-1275 5250);
FORCEPROP 1 LAST VOLTAGE 25V
J 2
(-1300 5200);
DISPLAY 0.510638 (-1300 5200);
FORCEPROP 1 LAST MATERIAL X7R
J 2
(-1300 5100);
DISPLAY 0.510638 (-1300 5100);
FORCEPROP 1 LAST TOLERANCE 10%
J 2
(-1300 5150);
DISPLAY 0.510638 (-1300 5150);
FORCEPROP 2 LAST CDS_LIB pure_quanta
J 0
(-1450 5175);
DISPLAY INVISIBLE (-1450 5175);
FORCEPROP 1 LAST PATH I165
J 2
(-1500 5325);
DISPLAY 0.978723 (-1500 5325);
PAINT WHITE (-1500 5325);
DISPLAY INVISIBLE (-1500 5325);
FORCEPROP 1 LAST PART_NUMBER CH4104K1B00
J 2
(-1150 5050);
DISPLAY 0.510638 (-1150 5050);
DISPLAY INVISIBLE (-1150 5050);
FORCEADD Q_CAP..1
(-1075 5175);
FORCEPROP 1 LAST LOCATION C1077
J 0
(-1025 5275);
DISPLAY 0.510638 (-1025 5275);
FORCEPROP 2 LAST $SEC 1
J 0
(-1025 5375);
DISPLAY 0.680851 (-1025 5375);
PAINT MONO (-1025 5375);
DISPLAY INVISIBLE (-1025 5375);
FORCEPROP 2 LAST CDS_SEC 1
J 0
(-1025 5375);
DISPLAY 1.021277 (-1025 5375);
DISPLAY INVISIBLE (-1025 5375);
FORCEPROP 1 LASTPIN (-1075 5275) $PN 1
J 0
(-1065 5255);
DISPLAY 0.787234 (-1065 5255);
FORCEPROP 1 LASTPIN (-1075 5075) $PN 2
J 0
(-1065 5055);
DISPLAY 0.787234 (-1065 5055);
FORCEPROP 1 LAST MATERIAL X6S
J 0
(-1025 5075);
DISPLAY 0.510638 (-1025 5075);
FORCEPROP 1 LAST PACK_TYPE C0805
J 0
(-1025 4975);
DISPLAY 0.510638 (-1025 4975);
FORCEPROP 1 LAST VALUE 10UF
J 0
(-1025 5225);
DISPLAY 0.510638 (-1025 5225);
FORCEPROP 1 LAST VOLTAGE 16V
J 0
(-1025 5175);
DISPLAY 0.510638 (-1025 5175);
FORCEPROP 1 LAST TOLERANCE 10%
J 0
(-1025 5125);
DISPLAY 0.510638 (-1025 5125);
FORCEPROP 2 LAST CDS_LIB pure_quanta
J 0
(-1075 5175);
PAINT MONO (-1075 5175);
DISPLAY INVISIBLE (-1075 5175);
FORCEPROP 1 LAST PATH I166
J 0
(-1025 5325);
DISPLAY 0.978723 (-1025 5325);
PAINT WHITE (-1025 5325);
DISPLAY INVISIBLE (-1025 5325);
FORCEPROP 1 LAST PART_NUMBER CH6103KEA00
J 0
(-1025 5025);
DISPLAY 0.510638 (-1025 5025);
DISPLAY INVISIBLE (-1025 5025);
FORCEADD UNIVERSAL_GND..1
(-1075 5000);
FORCEPROP 3 LASTPIN (-1075 5050) SIG_NAME GND\g
J 0
(-1065 5060);
DISPLAY 0.659574 (-1065 5060);
PAINT MONO (-1065 5060);
DISPLAY INVISIBLE (-1065 5060);
FORCEPROP 2 LAST CDS_LIB pure_quanta_power
J 0
(-1075 5000);
DISPLAY INVISIBLE (-1075 5000);
FORCEPROP 1 LAST HDL_POWER GND
J 1
(-1050 4925);
DISPLAY 0.872340 (-1050 4925);
PAINT GREEN (-1050 4925);
DISPLAY INVISIBLE (-1050 4925);
FORCEPROP 1 LAST PATH I167
J 0
(-1000 5000);
DISPLAY 0.872340 (-1000 5000);
PAINT AQUA (-1000 5000);
DISPLAY INVISIBLE (-1000 5000);
FORCEADD Q_INDUCTOR..1
(-750 5400);
FORCEPROP 1 LAST LOCATION L24
J 0
(-850 5560);
DISPLAY 0.382979 (-850 5560);
PAINT GREEN (-850 5560);
FORCEPROP 2 LAST $SEC 1
J 0
(-850 5675);
DISPLAY 0.680851 (-850 5675);
PAINT MONO (-850 5675);
DISPLAY INVISIBLE (-850 5675);
FORCEPROP 2 LAST CDS_SEC 1
J 0
(-850 5675);
DISPLAY 1.021277 (-850 5675);
DISPLAY INVISIBLE (-850 5675);
FORCEPROP 2 LASTPIN (-850 5375) $PN 1
J 2
(-860 5385);
DISPLAY 0.680851 (-860 5385);
PAINT MONO (-860 5385);
FORCEPROP 2 LASTPIN (-650 5375) $PN 2
J 0
(-640 5385);
DISPLAY 0.680851 (-640 5385);
PAINT MONO (-640 5385);
FORCEPROP 1 LAST MATERIAL IND
J 0
(-850 5455);
DISPLAY 0.382979 (-850 5455);
PAINT GREEN (-850 5455);
FORCEPROP 2 LAST VALUE BLM18PG300SN1D 
J 0
(-850 5650);
DISPLAY 0.510638 (-850 5650);
FORCEPROP 2 LAST PACK_TYPE SMLF
J 0
(-850 5600);
DISPLAY 0.510638 (-850 5600);
FORCEPROP 1 LAST NEEDS_NO_SIZE TRUE
J 0
(-750 5400);
DISPLAY 0.468085 (-750 5400);
PAINT GREEN (-750 5400);
DISPLAY INVISIBLE (-750 5400);
FORCEPROP 2 LAST CDS_LIB pure_quanta
J 0
(-750 5400);
DISPLAY INVISIBLE (-750 5400);
FORCEPROP 1 LAST PATH I168
J 0
(-675 5455);
DISPLAY 0.723404 (-675 5455);
PAINT GREEN (-675 5455);
DISPLAY INVISIBLE (-675 5455);
FORCEPROP 1 LAST PART_NUMBER TMP_QCX8PG300001
J 0
(-850 5510);
DISPLAY 0.382979 (-850 5510);
PAINT GREEN (-850 5510);
DISPLAY INVISIBLE (-850 5510);
FORCEADD UNIVERSAL_POWER..1
(-325 5600);
FORCEPROP 3 LASTPIN (-325 5550) SIG_NAME P3V3_AUX\g
J 0
(-315 5560);
DISPLAY 0.659574 (-315 5560);
PAINT MONO (-315 5560);
DISPLAY INVISIBLE (-315 5560);
FORCEPROP 1 LAST HDL_POWER P3V3_AUX
J 1
(-325 5650);
DISPLAY 0.872340 (-325 5650);
PAINT GREEN (-325 5650);
FORCEPROP 2 LAST CDS_LIB pure_quanta_power
J 0
(-325 5600);
DISPLAY INVISIBLE (-325 5600);
FORCEPROP 1 LAST PATH I169
J 0
(-275 5625);
DISPLAY 0.872340 (-275 5625);
PAINT AQUA (-275 5625);
DISPLAY INVISIBLE (-275 5625);
FORCEADD UNIVERSAL_POWER..1
(-8950 3475);
FORCEPROP 3 LASTPIN (-8950 3425) SIG_NAME P1V2_AUX\g
J 0
(-8940 3435);
DISPLAY 0.659574 (-8940 3435);
PAINT MONO (-8940 3435);
DISPLAY INVISIBLE (-8940 3435);
FORCEPROP 1 LAST HDL_POWER P1V2_AUX
J 1
(-8950 3525);
DISPLAY 0.872340 (-8950 3525);
PAINT GREEN (-8950 3525);
FORCEPROP 2 LAST CDS_LIB pure_quanta_power
J 0
(-8950 3475);
DISPLAY INVISIBLE (-8950 3475);
FORCEPROP 1 LAST PATH I170
J 0
(-8900 3500);
DISPLAY 0.872340 (-8900 3500);
PAINT AQUA (-8900 3500);
DISPLAY INVISIBLE (-8900 3500);
FORCEADD OFFPAGE..2
(-7450 2975);
FORCEPROP 2 LAST $XR0 259 
J 0
(-7261 2975);
DISPLAY 0.638298 (-7261 2975);
PAINT MONO (-7261 2975);
FORCEPROP 2 LAST CDS_LIB standard
J 0
(-7450 2975);
DISPLAY INVISIBLE (-7450 2975);
FORCEPROP 1 LAST OFFPAGE TRUE
J 0
(-7125 2850);
DISPLAY 0.872340 (-7125 2850);
DISPLAY INVISIBLE (-7125 2850);
FORCEPROP 1 LAST COMMENT_BODY TRUE
J 0
(-7495 2880);
DISPLAY 0.872340 (-7495 2880);
PAINT GREEN (-7495 2880);
DISPLAY INVISIBLE (-7495 2880);
FORCEPROP 2 LAST PATH I171
J 0
(-7250 3025);
DISPLAY 0.680851 (-7250 3025);
DISPLAY INVISIBLE (-7250 3025);
FORCEADD OFFPAGE..2
(-7450 2825);
FORCEPROP 2 LAST $XR0 259 
J 0
(-7261 2825);
DISPLAY 0.638298 (-7261 2825);
PAINT MONO (-7261 2825);
FORCEPROP 2 LAST CDS_LIB standard
J 0
(-7450 2825);
DISPLAY INVISIBLE (-7450 2825);
FORCEPROP 1 LAST OFFPAGE TRUE
J 0
(-7125 2700);
DISPLAY 0.872340 (-7125 2700);
DISPLAY INVISIBLE (-7125 2700);
FORCEPROP 1 LAST COMMENT_BODY TRUE
J 0
(-7495 2730);
DISPLAY 0.872340 (-7495 2730);
PAINT GREEN (-7495 2730);
DISPLAY INVISIBLE (-7495 2730);
FORCEPROP 2 LAST PATH I172
J 0
(-7250 2875);
DISPLAY 0.680851 (-7250 2875);
DISPLAY INVISIBLE (-7250 2875);
FORCEADD Q_CAP..1
(-7525 2575);
FORCEPROP 1 LAST LOCATION C1078
J 0
(-7475 2675);
DISPLAY 0.510638 (-7475 2675);
FORCEPROP 2 LAST $SEC 1
J 0
(-7475 2775);
DISPLAY 0.680851 (-7475 2775);
PAINT MONO (-7475 2775);
DISPLAY INVISIBLE (-7475 2775);
FORCEPROP 0 LAST CDS_SEC 1
J 0
(-7475 2750);
DISPLAY 1.021277 (-7475 2750);
DISPLAY INVISIBLE (-7475 2750);
FORCEPROP 1 LASTPIN (-7525 2675) $PN 1
J 0
(-7515 2655);
DISPLAY 0.787234 (-7515 2655);
PAINT MONO (-7515 2655);
FORCEPROP 1 LASTPIN (-7525 2475) $PN 2
J 0
(-7515 2455);
DISPLAY 0.787234 (-7515 2455);
PAINT MONO (-7515 2455);
FORCEPROP 1 LAST VOLTAGE 50V
J 0
(-7475 2575);
DISPLAY 0.510638 (-7475 2575);
FORCEPROP 1 LAST TOLERANCE 5%
J 0
(-7475 2525);
DISPLAY 0.510638 (-7475 2525);
FORCEPROP 1 LAST PACK_TYPE 0402
J 0
(-7475 2375);
DISPLAY 0.510638 (-7475 2375);
FORCEPROP 1 LAST VALUE 100PF
J 0
(-7475 2625);
DISPLAY 0.510638 (-7475 2625);
FORCEPROP 1 LAST MATERIAL EMPTY
J 0
(-7475 2475);
DISPLAY 0.510638 (-7475 2475);
FORCEPROP 0 LAST ROOM ADC_MAM_BOM2
J 0
(-7475 2325);
DISPLAY 0.553191 (-7475 2325);
PAINT RED (-7475 2325);
FORCEPROP 2 LAST CDS_LIB pure_quanta
J 0
(-7525 2575);
DISPLAY INVISIBLE (-7525 2575);
FORCEPROP 1 LAST PATH I173
J 0
(-7475 2725);
DISPLAY 0.978723 (-7475 2725);
PAINT WHITE (-7475 2725);
DISPLAY INVISIBLE (-7475 2725);
FORCEPROP 1 LAST PART_NUMBER CH11006JB18
J 0
(-7475 2425);
DISPLAY 0.510638 (-7475 2425);
DISPLAY INVISIBLE (-7475 2425);
FORCEADD UNIVERSAL_GND..1
(-7525 2300);
FORCEPROP 3 LASTPIN (-7525 2350) SIG_NAME GND\g
J 0
(-7515 2360);
DISPLAY 0.659574 (-7515 2360);
PAINT MONO (-7515 2360);
DISPLAY INVISIBLE (-7515 2360);
FORCEPROP 2 LAST CDS_LIB pure_quanta_power
J 0
(-7525 2300);
DISPLAY INVISIBLE (-7525 2300);
FORCEPROP 1 LAST HDL_POWER GND
J 1
(-7500 2225);
DISPLAY 0.872340 (-7500 2225);
PAINT GREEN (-7500 2225);
DISPLAY INVISIBLE (-7500 2225);
FORCEPROP 1 LAST PATH I174
J 0
(-7450 2300);
DISPLAY 0.872340 (-7450 2300);
PAINT AQUA (-7450 2300);
DISPLAY INVISIBLE (-7450 2300);
FORCEADD Q_CAP..1
R 2
(-7875 2575);
FORCEPROP 1 LAST LOCATION C1086
J 2
(-7700 2675);
DISPLAY 0.638298 (-7700 2675);
FORCEPROP 0 LAST $SEC 1
J 0
(-7775 2725);
DISPLAY 0.680851 (-7775 2725);
PAINT MONO (-7775 2725);
DISPLAY INVISIBLE (-7775 2725);
FORCEPROP 0 LAST CDS_SEC 1
J 0
(-7775 2725);
DISPLAY 1.021277 (-7775 2725);
DISPLAY INVISIBLE (-7775 2725);
FORCEPROP 1 LASTPIN (-7875 2675) $PN 1
J 2
(-7885 2655);
DISPLAY 0.787234 (-7885 2655);
PAINT MONO (-7885 2655);
FORCEPROP 1 LASTPIN (-7875 2475) $PN 2
J 2
(-7885 2455);
DISPLAY 0.787234 (-7885 2455);
PAINT MONO (-7885 2455);
FORCEPROP 0 LAST ROOM ADC_TI_BOM1
J 0
(-7850 2350);
DISPLAY 0.553191 (-7850 2350);
PAINT RED (-7850 2350);
FORCEPROP 1 LAST PACK_TYPE 0402
J 2
(-7700 2400);
DISPLAY 0.510638 (-7700 2400);
FORCEPROP 1 LAST MATERIAL X7R
J 2
(-7725 2500);
DISPLAY 0.510638 (-7725 2500);
PAINT RED (-7725 2500);
FORCEPROP 1 LAST TOLERANCE 10%
J 2
(-7725 2550);
DISPLAY 0.510638 (-7725 2550);
FORCEPROP 1 LAST VOLTAGE 25V
J 2
(-7725 2600);
DISPLAY 0.510638 (-7725 2600);
FORCEPROP 1 LAST VALUE 0.1UF
J 2
(-7700 2650);
DISPLAY 0.510638 (-7700 2650);
FORCEPROP 2 LAST CDS_LIB pure_quanta
J 0
(-7875 2575);
DISPLAY INVISIBLE (-7875 2575);
FORCEPROP 1 LAST PATH I175
J 2
(-7925 2725);
DISPLAY 0.978723 (-7925 2725);
PAINT WHITE (-7925 2725);
DISPLAY INVISIBLE (-7925 2725);
FORCEPROP 1 LAST PART_NUMBER CH4104K1B00
J 2
(-7575 2450);
DISPLAY 0.510638 (-7575 2450);
DISPLAY INVISIBLE (-7575 2450);
FORCEADD UNIVERSAL_GND..1
(-7875 2300);
FORCEPROP 3 LASTPIN (-7875 2350) SIG_NAME GND\g
J 0
(-7865 2360);
DISPLAY 0.659574 (-7865 2360);
PAINT MONO (-7865 2360);
DISPLAY INVISIBLE (-7865 2360);
FORCEPROP 2 LAST CDS_LIB pure_quanta_power
J 0
(-7875 2300);
DISPLAY INVISIBLE (-7875 2300);
FORCEPROP 1 LAST HDL_POWER GND
J 1
(-7850 2225);
DISPLAY 0.872340 (-7850 2225);
PAINT GREEN (-7850 2225);
DISPLAY INVISIBLE (-7850 2225);
FORCEPROP 1 LAST PATH I176
J 0
(-7800 2300);
DISPLAY 0.872340 (-7800 2300);
PAINT AQUA (-7800 2300);
DISPLAY INVISIBLE (-7800 2300);
FORCEADD Q_RES..1
(-8250 2975);
FORCEPROP 1 LAST LOCATION R1245
J 0
(-8450 2975);
DISPLAY 0.510638 (-8450 2975);
FORCEPROP 0 LAST $SEC 1
J 0
(-8375 3025);
DISPLAY 0.680851 (-8375 3025);
PAINT MONO (-8375 3025);
DISPLAY INVISIBLE (-8375 3025);
FORCEPROP 0 LAST CDS_SEC 1
J 0
(-8375 3025);
DISPLAY 1.021277 (-8375 3025);
DISPLAY INVISIBLE (-8375 3025);
FORCEPROP 1 LASTPIN (-8350 2975) $PN 1
J 0
(-8338 2987);
DISPLAY 0.787234 (-8338 2987);
PAINT MONO (-8338 2987);
FORCEPROP 1 LASTPIN (-8150 2975) $PN 2
J 0
(-8188 2987);
DISPLAY 0.787234 (-8188 2987);
PAINT MONO (-8188 2987);
FORCEPROP 1 LAST VALUE 0
J 2
(-8100 2975);
DISPLAY 0.404255 (-8100 2975);
FORCEPROP 1 LAST MATERIAL EMPTY
J 0
(-8025 2975);
DISPLAY 0.404255 (-8025 2975);
FORCEPROP 1 LAST TOLERANCE 5%
J 0
(-8075 2975);
DISPLAY 0.404255 (-8075 2975);
FORCEPROP 0 LAST ROOM ADC_MAM_BOM2
J 0
(-8425 3075);
DISPLAY 0.680851 (-8425 3075);
PAINT RED (-8425 3075);
FORCEPROP 1 LAST PACK_TYPE 0402LF
J 0
(-8000 2975);
DISPLAY 0.510638 (-8000 2975);
DISPLAY INVISIBLE (-8000 2975);
FORCEPROP 1 LAST WATTAGE 1/16W
J 2
(-8150 2900);
DISPLAY 0.319149 (-8150 2900);
DISPLAY INVISIBLE (-8150 2900);
FORCEPROP 2 LAST CDS_LIB pure_quanta
J 0
(-8250 2975);
DISPLAY INVISIBLE (-8250 2975);
FORCEPROP 1 LAST PATH I177
J 0
(-8300 3125);
DISPLAY 0.978723 (-8300 3125);
PAINT WHITE (-8300 3125);
DISPLAY INVISIBLE (-8300 3125);
FORCEPROP 1 LAST PART_NUMBER CS00002JB13
J 0
(-8325 2925);
DISPLAY 0.319149 (-8325 2925);
DISPLAY INVISIBLE (-8325 2925);
FORCEADD Q_RES..1
(-8250 2825);
FORCEPROP 1 LAST LOCATION R1251
J 0
(-8450 2825);
DISPLAY 0.510638 (-8450 2825);
FORCEPROP 0 LAST $SEC 1
J 0
(-8375 2875);
DISPLAY 0.680851 (-8375 2875);
PAINT MONO (-8375 2875);
DISPLAY INVISIBLE (-8375 2875);
FORCEPROP 0 LAST CDS_SEC 1
J 0
(-8375 2875);
DISPLAY 1.021277 (-8375 2875);
DISPLAY INVISIBLE (-8375 2875);
FORCEPROP 1 LASTPIN (-8350 2825) $PN 1
J 0
(-8338 2837);
DISPLAY 0.787234 (-8338 2837);
PAINT MONO (-8338 2837);
FORCEPROP 1 LASTPIN (-8150 2825) $PN 2
J 0
(-8188 2837);
DISPLAY 0.787234 (-8188 2837);
PAINT MONO (-8188 2837);
FORCEPROP 0 LAST ROOM ADC_TI_BOM1
J 0
(-8425 2750);
DISPLAY 0.680851 (-8425 2750);
PAINT RED (-8425 2750);
FORCEPROP 1 LAST VALUE 0
J 2
(-8100 2825);
DISPLAY 0.404255 (-8100 2825);
FORCEPROP 1 LAST MATERIAL CHIP
J 0
(-8025 2825);
DISPLAY 0.404255 (-8025 2825);
PAINT RED (-8025 2825);
FORCEPROP 1 LAST TOLERANCE 5%
J 0
(-8075 2825);
DISPLAY 0.404255 (-8075 2825);
FORCEPROP 1 LAST PACK_TYPE 0402LF
J 0
(-8000 2825);
DISPLAY 0.510638 (-8000 2825);
DISPLAY INVISIBLE (-8000 2825);
FORCEPROP 1 LAST WATTAGE 1/16W
J 2
(-8150 2750);
DISPLAY 0.319149 (-8150 2750);
DISPLAY INVISIBLE (-8150 2750);
FORCEPROP 2 LAST CDS_LIB pure_quanta
J 0
(-8250 2825);
DISPLAY INVISIBLE (-8250 2825);
FORCEPROP 1 LAST PATH I178
J 0
(-8300 2975);
DISPLAY 0.978723 (-8300 2975);
PAINT WHITE (-8300 2975);
DISPLAY INVISIBLE (-8300 2975);
FORCEPROP 1 LAST PART_NUMBER CS00002JB13
J 0
(-8325 2775);
DISPLAY 0.319149 (-8325 2775);
DISPLAY INVISIBLE (-8325 2775);
FORCEADD Q_RES..2
(-8950 3225);
FORCEPROP 1 LAST LOCATION R1232
J 0
(-8905 3350);
DISPLAY 0.510638 (-8905 3350);
FORCEPROP 2 LAST $SEC 1
J 0
(-8900 3450);
DISPLAY 0.680851 (-8900 3450);
PAINT MONO (-8900 3450);
DISPLAY INVISIBLE (-8900 3450);
FORCEPROP 2 LAST CDS_SEC 1
J 0
(-8900 3450);
DISPLAY 1.021277 (-8900 3450);
DISPLAY INVISIBLE (-8900 3450);
FORCEPROP 1 LASTPIN (-8950 3325) $PN 1
J 0
(-8945 3287);
DISPLAY 0.787234 (-8945 3287);
PAINT MONO (-8945 3287);
FORCEPROP 1 LASTPIN (-8950 3125) $PN 2
J 0
(-8945 3135);
DISPLAY 0.787234 (-8945 3135);
PAINT MONO (-8945 3135);
FORCEPROP 1 LAST MATERIAL CHIP
J 0
(-8910 3150);
DISPLAY 0.510638 (-8910 3150);
FORCEPROP 1 LAST WATTAGE 1/16W
J 0
(-8910 3200);
DISPLAY 0.510638 (-8910 3200);
FORCEPROP 1 LAST TOLERANCE 1%
J 0
(-8905 3250);
DISPLAY 0.510638 (-8905 3250);
FORCEPROP 1 LAST VALUE 5.11K
J 0
(-8905 3300);
DISPLAY 0.510638 (-8905 3300);
FORCEPROP 1 LAST PACK_TYPE 0402LF
J 0
(-8910 3050);
DISPLAY 0.510638 (-8910 3050);
FORCEPROP 2 LAST CDS_LIB pure_quanta
J 0
(-8950 3225);
DISPLAY INVISIBLE (-8950 3225);
FORCEPROP 1 LAST PATH I179
J 0
(-8900 3400);
DISPLAY 0.978723 (-8900 3400);
PAINT WHITE (-8900 3400);
DISPLAY INVISIBLE (-8900 3400);
FORCEPROP 1 LAST PART_NUMBER CS25112FB04
J 0
(-8910 3100);
DISPLAY 0.510638 (-8910 3100);
DISPLAY INVISIBLE (-8910 3100);
FORCEADD UNIVERSAL_GND..1
(-8975 3975);
FORCEPROP 3 LASTPIN (-8975 4025) SIG_NAME GND\g
J 0
(-8965 4035);
DISPLAY 0.659574 (-8965 4035);
PAINT MONO (-8965 4035);
DISPLAY INVISIBLE (-8965 4035);
FORCEPROP 2 LAST CDS_LIB pure_quanta_power
J 0
(-8975 3975);
DISPLAY INVISIBLE (-8975 3975);
FORCEPROP 1 LAST HDL_POWER GND
J 1
(-8950 3900);
DISPLAY 0.872340 (-8950 3900);
PAINT GREEN (-8950 3900);
DISPLAY INVISIBLE (-8950 3900);
FORCEPROP 1 LAST PATH I18
J 0
(-8900 3975);
DISPLAY 0.872340 (-8900 3975);
PAINT AQUA (-8900 3975);
DISPLAY INVISIBLE (-8900 3975);
FORCEADD UNIVERSAL_GND..1
(-8950 2350);
FORCEPROP 3 LASTPIN (-8950 2400) SIG_NAME GND\g
J 0
(-8940 2410);
DISPLAY 0.659574 (-8940 2410);
PAINT MONO (-8940 2410);
DISPLAY INVISIBLE (-8940 2410);
FORCEPROP 2 LAST CDS_LIB pure_quanta_power
J 0
(-8950 2350);
DISPLAY INVISIBLE (-8950 2350);
FORCEPROP 1 LAST HDL_POWER GND
J 1
(-8925 2275);
DISPLAY 0.872340 (-8925 2275);
PAINT GREEN (-8925 2275);
DISPLAY INVISIBLE (-8925 2275);
FORCEPROP 1 LAST PATH I181
J 0
(-8875 2350);
DISPLAY 0.872340 (-8875 2350);
PAINT AQUA (-8875 2350);
DISPLAY INVISIBLE (-8875 2350);
FORCEADD OFFPAGE..2
(-7200 1225);
FORCEPROP 2 LAST $XR0 259 
J 0
(-7011 1225);
DISPLAY 0.638298 (-7011 1225);
PAINT MONO (-7011 1225);
FORCEPROP 2 LAST CDS_LIB standard
J 0
(-7200 1225);
DISPLAY INVISIBLE (-7200 1225);
FORCEPROP 1 LAST OFFPAGE TRUE
J 0
(-6875 1100);
DISPLAY 0.872340 (-6875 1100);
DISPLAY INVISIBLE (-6875 1100);
FORCEPROP 1 LAST COMMENT_BODY TRUE
J 0
(-7245 1130);
DISPLAY 0.872340 (-7245 1130);
PAINT GREEN (-7245 1130);
DISPLAY INVISIBLE (-7245 1130);
FORCEPROP 2 LAST PATH I182
J 0
(-7000 1275);
DISPLAY 0.680851 (-7000 1275);
DISPLAY INVISIBLE (-7000 1275);
FORCEADD UNIVERSAL_POWER..1
(-9025 1875);
FORCEPROP 3 LASTPIN (-9025 1825) SIG_NAME P1V8_CPU0_RT_1D\g
J 0
(-9015 1835);
DISPLAY 0.659574 (-9015 1835);
PAINT MONO (-9015 1835);
DISPLAY INVISIBLE (-9015 1835);
FORCEPROP 1 LAST HDL_POWER P1V8_CPU0_RT_1D
J 1
(-9025 1925);
DISPLAY 0.702128 (-9025 1925);
PAINT GREEN (-9025 1925);
FORCEPROP 2 LAST CDS_LIB pure_quanta_power
J 0
(-9025 1875);
DISPLAY INVISIBLE (-9025 1875);
FORCEPROP 1 LAST PATH I183
J 0
(-8975 1900);
DISPLAY 0.872340 (-8975 1900);
PAINT AQUA (-8975 1900);
DISPLAY INVISIBLE (-8975 1900);
FORCEADD OFFPAGE..2
(-7225 1375);
FORCEPROP 2 LAST $XR0 259 
J 0
(-7036 1375);
DISPLAY 0.638298 (-7036 1375);
PAINT MONO (-7036 1375);
FORCEPROP 2 LAST CDS_LIB standard
J 0
(-7225 1375);
DISPLAY INVISIBLE (-7225 1375);
FORCEPROP 1 LAST OFFPAGE TRUE
J 0
(-6900 1250);
DISPLAY 0.872340 (-6900 1250);
DISPLAY INVISIBLE (-6900 1250);
FORCEPROP 1 LAST COMMENT_BODY TRUE
J 0
(-7270 1280);
DISPLAY 0.872340 (-7270 1280);
PAINT GREEN (-7270 1280);
DISPLAY INVISIBLE (-7270 1280);
FORCEPROP 2 LAST PATH I184
J 0
(-7025 1425);
DISPLAY 0.680851 (-7025 1425);
DISPLAY INVISIBLE (-7025 1425);
FORCEADD Q_CAP..1
(-7300 975);
FORCEPROP 1 LAST LOCATION C1079
J 0
(-7250 1075);
DISPLAY 0.510638 (-7250 1075);
FORCEPROP 2 LAST $SEC 1
J 0
(-7250 1175);
DISPLAY 0.680851 (-7250 1175);
PAINT MONO (-7250 1175);
DISPLAY INVISIBLE (-7250 1175);
FORCEPROP 0 LAST CDS_SEC 1
J 0
(-7250 1150);
DISPLAY 1.021277 (-7250 1150);
DISPLAY INVISIBLE (-7250 1150);
FORCEPROP 1 LASTPIN (-7300 1075) $PN 1
J 0
(-7290 1055);
DISPLAY 0.787234 (-7290 1055);
PAINT MONO (-7290 1055);
FORCEPROP 1 LASTPIN (-7300 875) $PN 2
J 0
(-7290 855);
DISPLAY 0.787234 (-7290 855);
PAINT MONO (-7290 855);
FORCEPROP 1 LAST VOLTAGE 50V
J 0
(-7250 975);
DISPLAY 0.510638 (-7250 975);
FORCEPROP 1 LAST VALUE 100PF
J 0
(-7250 1025);
DISPLAY 0.510638 (-7250 1025);
FORCEPROP 1 LAST PACK_TYPE 0402
J 0
(-7250 775);
DISPLAY 0.510638 (-7250 775);
FORCEPROP 1 LAST MATERIAL EMPTY
J 0
(-7250 875);
DISPLAY 0.510638 (-7250 875);
FORCEPROP 1 LAST TOLERANCE 5%
J 0
(-7250 925);
DISPLAY 0.510638 (-7250 925);
FORCEPROP 0 LAST ROOM ADC_MAM_BOM2
J 0
(-7250 1125);
DISPLAY 0.680851 (-7250 1125);
PAINT RED (-7250 1125);
FORCEPROP 2 LAST CDS_LIB pure_quanta
J 0
(-7300 975);
DISPLAY INVISIBLE (-7300 975);
FORCEPROP 1 LAST PATH I185
J 0
(-7250 1125);
DISPLAY 0.978723 (-7250 1125);
PAINT WHITE (-7250 1125);
DISPLAY INVISIBLE (-7250 1125);
FORCEPROP 1 LAST PART_NUMBER CH11006JB18
J 0
(-7250 825);
DISPLAY 0.510638 (-7250 825);
DISPLAY INVISIBLE (-7250 825);
FORCEADD UNIVERSAL_GND..1
(-7300 700);
FORCEPROP 3 LASTPIN (-7300 750) SIG_NAME GND\g
J 0
(-7290 760);
DISPLAY 0.659574 (-7290 760);
PAINT MONO (-7290 760);
DISPLAY INVISIBLE (-7290 760);
FORCEPROP 2 LAST CDS_LIB pure_quanta_power
J 0
(-7300 700);
DISPLAY INVISIBLE (-7300 700);
FORCEPROP 1 LAST HDL_POWER GND
J 1
(-7275 625);
DISPLAY 0.872340 (-7275 625);
PAINT GREEN (-7275 625);
DISPLAY INVISIBLE (-7275 625);
FORCEPROP 1 LAST PATH I186
J 0
(-7225 700);
DISPLAY 0.872340 (-7225 700);
PAINT AQUA (-7225 700);
DISPLAY INVISIBLE (-7225 700);
FORCEADD Q_CAP..1
R 2
(-7825 975);
FORCEPROP 1 LAST LOCATION C1087
J 2
(-7650 1075);
DISPLAY 0.638298 (-7650 1075);
FORCEPROP 0 LAST $SEC 1
J 0
(-7725 1125);
DISPLAY 0.680851 (-7725 1125);
PAINT MONO (-7725 1125);
DISPLAY INVISIBLE (-7725 1125);
FORCEPROP 0 LAST CDS_SEC 1
J 0
(-7725 1125);
DISPLAY 1.021277 (-7725 1125);
DISPLAY INVISIBLE (-7725 1125);
FORCEPROP 1 LASTPIN (-7825 1075) $PN 1
J 2
(-7835 1055);
DISPLAY 0.787234 (-7835 1055);
PAINT MONO (-7835 1055);
FORCEPROP 1 LASTPIN (-7825 875) $PN 2
J 2
(-7835 855);
DISPLAY 0.787234 (-7835 855);
PAINT MONO (-7835 855);
FORCEPROP 1 LAST TOLERANCE 10%
J 2
(-7675 950);
DISPLAY 0.510638 (-7675 950);
FORCEPROP 1 LAST MATERIAL X7R
J 2
(-7675 900);
DISPLAY 0.510638 (-7675 900);
PAINT RED (-7675 900);
FORCEPROP 1 LAST VOLTAGE 25V
J 2
(-7675 1000);
DISPLAY 0.510638 (-7675 1000);
FORCEPROP 1 LAST PACK_TYPE 0402
J 2
(-7650 800);
DISPLAY 0.510638 (-7650 800);
FORCEPROP 1 LAST VALUE 0.1UF
J 2
(-7650 1050);
DISPLAY 0.510638 (-7650 1050);
FORCEPROP 0 LAST ROOM ADC_TI_BOM1
J 0
(-7800 1125);
DISPLAY 0.680851 (-7800 1125);
PAINT RED (-7800 1125);
FORCEPROP 2 LAST CDS_LIB pure_quanta
J 0
(-7825 975);
DISPLAY INVISIBLE (-7825 975);
FORCEPROP 1 LAST PATH I187
J 2
(-7875 1125);
DISPLAY 0.978723 (-7875 1125);
PAINT WHITE (-7875 1125);
DISPLAY INVISIBLE (-7875 1125);
FORCEPROP 1 LAST PART_NUMBER CH4104K1B00
J 2
(-7525 850);
DISPLAY 0.510638 (-7525 850);
DISPLAY INVISIBLE (-7525 850);
FORCEADD UNIVERSAL_GND..1
(-7825 700);
FORCEPROP 3 LASTPIN (-7825 750) SIG_NAME GND\g
J 0
(-7815 760);
DISPLAY 0.659574 (-7815 760);
PAINT MONO (-7815 760);
DISPLAY INVISIBLE (-7815 760);
FORCEPROP 2 LAST CDS_LIB pure_quanta_power
J 0
(-7825 700);
DISPLAY INVISIBLE (-7825 700);
FORCEPROP 1 LAST HDL_POWER GND
J 1
(-7800 625);
DISPLAY 0.872340 (-7800 625);
PAINT GREEN (-7800 625);
DISPLAY INVISIBLE (-7800 625);
FORCEPROP 1 LAST PATH I188
J 0
(-7750 700);
DISPLAY 0.872340 (-7750 700);
PAINT AQUA (-7750 700);
DISPLAY INVISIBLE (-7750 700);
FORCEADD Q_RES..1
(-8200 1375);
FORCEPROP 1 LAST LOCATION R1246
J 0
(-8400 1375);
DISPLAY 0.510638 (-8400 1375);
FORCEPROP 0 LAST $SEC 1
J 0
(-8325 1425);
DISPLAY 0.680851 (-8325 1425);
PAINT MONO (-8325 1425);
DISPLAY INVISIBLE (-8325 1425);
FORCEPROP 0 LAST CDS_SEC 1
J 0
(-8325 1425);
DISPLAY 1.021277 (-8325 1425);
DISPLAY INVISIBLE (-8325 1425);
FORCEPROP 1 LASTPIN (-8300 1375) $PN 1
J 0
(-8288 1387);
DISPLAY 0.787234 (-8288 1387);
PAINT MONO (-8288 1387);
FORCEPROP 1 LASTPIN (-8100 1375) $PN 2
J 0
(-8138 1387);
DISPLAY 0.787234 (-8138 1387);
PAINT MONO (-8138 1387);
FORCEPROP 1 LAST VALUE 0
J 2
(-8050 1375);
DISPLAY 0.404255 (-8050 1375);
FORCEPROP 1 LAST MATERIAL EMPTY
J 0
(-7975 1375);
DISPLAY 0.404255 (-7975 1375);
FORCEPROP 1 LAST TOLERANCE 5%
J 0
(-8025 1375);
DISPLAY 0.404255 (-8025 1375);
FORCEPROP 0 LAST ROOM ADC_MAM_BOM2
J 0
(-8375 1475);
DISPLAY 0.680851 (-8375 1475);
PAINT RED (-8375 1475);
FORCEPROP 1 LAST PACK_TYPE 0402LF
J 0
(-7950 1375);
DISPLAY 0.510638 (-7950 1375);
DISPLAY INVISIBLE (-7950 1375);
FORCEPROP 1 LAST WATTAGE 1/16W
J 2
(-8100 1300);
DISPLAY 0.319149 (-8100 1300);
DISPLAY INVISIBLE (-8100 1300);
FORCEPROP 2 LAST CDS_LIB pure_quanta
J 0
(-8200 1375);
DISPLAY INVISIBLE (-8200 1375);
FORCEPROP 1 LAST PATH I189
J 0
(-8250 1525);
DISPLAY 0.978723 (-8250 1525);
PAINT WHITE (-8250 1525);
DISPLAY INVISIBLE (-8250 1525);
FORCEPROP 1 LAST PART_NUMBER CS00002JB13
J 0
(-8275 1325);
DISPLAY 0.319149 (-8275 1325);
DISPLAY INVISIBLE (-8275 1325);
FORCEADD Q_RES..2
(-8975 4700);
FORCEPROP 1 LAST LOCATION R1237
J 0
(-8930 4825);
DISPLAY 0.510638 (-8930 4825);
FORCEPROP 2 LAST $SEC 1
J 0
(-8925 4925);
DISPLAY 0.680851 (-8925 4925);
PAINT MONO (-8925 4925);
DISPLAY INVISIBLE (-8925 4925);
FORCEPROP 2 LAST CDS_SEC 1
J 0
(-8925 4925);
DISPLAY 1.021277 (-8925 4925);
DISPLAY INVISIBLE (-8925 4925);
FORCEPROP 1 LASTPIN (-8975 4800) $PN 1
J 0
(-8970 4762);
DISPLAY 0.787234 (-8970 4762);
PAINT MONO (-8970 4762);
FORCEPROP 1 LASTPIN (-8975 4600) $PN 2
J 0
(-8970 4610);
DISPLAY 0.787234 (-8970 4610);
PAINT MONO (-8970 4610);
FORCEPROP 1 LAST TOLERANCE 1%
J 0
(-8930 4725);
DISPLAY 0.510638 (-8930 4725);
FORCEPROP 1 LAST VALUE 5.11K
J 0
(-8930 4775);
DISPLAY 0.510638 (-8930 4775);
FORCEPROP 1 LAST PACK_TYPE 0402LF
J 0
(-8935 4525);
DISPLAY 0.510638 (-8935 4525);
FORCEPROP 1 LAST MATERIAL CHIP
J 0
(-8935 4625);
DISPLAY 0.510638 (-8935 4625);
FORCEPROP 1 LAST WATTAGE 1/16W
J 0
(-8935 4675);
DISPLAY 0.510638 (-8935 4675);
FORCEPROP 2 LAST CDS_LIB pure_quanta
J 0
(-8975 4700);
DISPLAY INVISIBLE (-8975 4700);
FORCEPROP 1 LAST PATH I19
J 0
(-8925 4875);
DISPLAY 0.978723 (-8925 4875);
PAINT WHITE (-8925 4875);
DISPLAY INVISIBLE (-8925 4875);
FORCEPROP 1 LAST PART_NUMBER CS25112FB04
J 0
(-8935 4575);
DISPLAY 0.510638 (-8935 4575);
DISPLAY INVISIBLE (-8935 4575);
FORCEADD Q_RES..1
(-8200 1225);
FORCEPROP 1 LAST LOCATION R1252
J 0
(-8400 1225);
DISPLAY 0.510638 (-8400 1225);
FORCEPROP 0 LAST $SEC 1
J 0
(-8325 1275);
DISPLAY 0.680851 (-8325 1275);
PAINT MONO (-8325 1275);
DISPLAY INVISIBLE (-8325 1275);
FORCEPROP 0 LAST CDS_SEC 1
J 0
(-8325 1275);
DISPLAY 1.021277 (-8325 1275);
DISPLAY INVISIBLE (-8325 1275);
FORCEPROP 1 LASTPIN (-8300 1225) $PN 1
J 0
(-8288 1237);
DISPLAY 0.787234 (-8288 1237);
PAINT MONO (-8288 1237);
FORCEPROP 1 LASTPIN (-8100 1225) $PN 2
J 0
(-8138 1237);
DISPLAY 0.787234 (-8138 1237);
PAINT MONO (-8138 1237);
FORCEPROP 0 LAST ROOM ADC_TI_BOM1
J 0
(-8350 1150);
DISPLAY 0.680851 (-8350 1150);
PAINT RED (-8350 1150);
FORCEPROP 1 LAST MATERIAL CHIP
J 0
(-7975 1225);
DISPLAY 0.404255 (-7975 1225);
PAINT RED (-7975 1225);
FORCEPROP 1 LAST VALUE 0
J 2
(-8050 1225);
DISPLAY 0.404255 (-8050 1225);
FORCEPROP 1 LAST TOLERANCE 5%
J 0
(-8025 1225);
DISPLAY 0.404255 (-8025 1225);
FORCEPROP 1 LAST PACK_TYPE 0402LF
J 0
(-7950 1225);
DISPLAY 0.510638 (-7950 1225);
DISPLAY INVISIBLE (-7950 1225);
FORCEPROP 1 LAST WATTAGE 1/16W
J 2
(-8100 1150);
DISPLAY 0.319149 (-8100 1150);
DISPLAY INVISIBLE (-8100 1150);
FORCEPROP 2 LAST CDS_LIB pure_quanta
J 0
(-8200 1225);
DISPLAY INVISIBLE (-8200 1225);
FORCEPROP 1 LAST PATH I190
J 0
(-8250 1375);
DISPLAY 0.978723 (-8250 1375);
PAINT WHITE (-8250 1375);
DISPLAY INVISIBLE (-8250 1375);
FORCEPROP 1 LAST PART_NUMBER CS00002JB13
J 0
(-8275 1175);
DISPLAY 0.319149 (-8275 1175);
DISPLAY INVISIBLE (-8275 1175);
FORCEADD Q_RES..2
(-9025 1625);
FORCEPROP 1 LAST LOCATION R1231
J 0
(-8980 1750);
DISPLAY 0.510638 (-8980 1750);
FORCEPROP 2 LAST $SEC 1
J 0
(-8975 1850);
DISPLAY 0.680851 (-8975 1850);
PAINT MONO (-8975 1850);
DISPLAY INVISIBLE (-8975 1850);
FORCEPROP 2 LAST CDS_SEC 1
J 0
(-8975 1850);
DISPLAY 1.021277 (-8975 1850);
DISPLAY INVISIBLE (-8975 1850);
FORCEPROP 1 LASTPIN (-9025 1725) $PN 1
J 0
(-9020 1687);
DISPLAY 0.787234 (-9020 1687);
PAINT MONO (-9020 1687);
FORCEPROP 1 LASTPIN (-9025 1525) $PN 2
J 0
(-9020 1535);
DISPLAY 0.787234 (-9020 1535);
PAINT MONO (-9020 1535);
FORCEPROP 1 LAST TOLERANCE 1%
J 0
(-8980 1650);
DISPLAY 0.510638 (-8980 1650);
FORCEPROP 1 LAST WATTAGE 1/16W
J 0
(-8985 1600);
DISPLAY 0.510638 (-8985 1600);
FORCEPROP 1 LAST MATERIAL CHIP
J 0
(-8985 1550);
DISPLAY 0.510638 (-8985 1550);
FORCEPROP 1 LAST VALUE 5.11K
J 0
(-8980 1700);
DISPLAY 0.510638 (-8980 1700);
FORCEPROP 1 LAST PACK_TYPE 0402LF
J 0
(-8985 1450);
DISPLAY 0.510638 (-8985 1450);
FORCEPROP 2 LAST CDS_LIB pure_quanta
J 0
(-9025 1625);
DISPLAY INVISIBLE (-9025 1625);
FORCEPROP 1 LAST PATH I191
J 0
(-8975 1800);
DISPLAY 0.978723 (-8975 1800);
PAINT WHITE (-8975 1800);
DISPLAY INVISIBLE (-8975 1800);
FORCEPROP 1 LAST PART_NUMBER CS25112FB04
J 0
(-8985 1500);
DISPLAY 0.510638 (-8985 1500);
DISPLAY INVISIBLE (-8985 1500);
FORCEADD UNIVERSAL_GND..1
(-9025 750);
FORCEPROP 3 LASTPIN (-9025 800) SIG_NAME GND\g
J 0
(-9015 810);
DISPLAY 0.659574 (-9015 810);
PAINT MONO (-9015 810);
DISPLAY INVISIBLE (-9015 810);
FORCEPROP 2 LAST CDS_LIB pure_quanta_power
J 0
(-9025 750);
DISPLAY INVISIBLE (-9025 750);
FORCEPROP 1 LAST HDL_POWER GND
J 1
(-9000 675);
DISPLAY 0.872340 (-9000 675);
PAINT GREEN (-9000 675);
DISPLAY INVISIBLE (-9000 675);
FORCEPROP 1 LAST PATH I193
J 0
(-8950 750);
DISPLAY 0.872340 (-8950 750);
PAINT AQUA (-8950 750);
DISPLAY INVISIBLE (-8950 750);
FORCEADD Q_RES..2
(-6800 6000);
FORCEPROP 1 LAST LOCATION R1234
J 0
(-6755 6125);
DISPLAY 0.510638 (-6755 6125);
FORCEPROP 2 LAST $SEC 1
J 0
(-6750 6225);
DISPLAY 0.680851 (-6750 6225);
PAINT MONO (-6750 6225);
DISPLAY INVISIBLE (-6750 6225);
FORCEPROP 2 LAST CDS_SEC 1
J 0
(-6750 6225);
DISPLAY 1.021277 (-6750 6225);
DISPLAY INVISIBLE (-6750 6225);
FORCEPROP 1 LASTPIN (-6800 6100) $PN 1
J 0
(-6795 6062);
DISPLAY 0.787234 (-6795 6062);
PAINT MONO (-6795 6062);
FORCEPROP 1 LASTPIN (-6800 5900) $PN 2
J 0
(-6795 5910);
DISPLAY 0.787234 (-6795 5910);
PAINT MONO (-6795 5910);
FORCEPROP 1 LAST VALUE 5.11K
J 0
(-6755 6075);
DISPLAY 0.510638 (-6755 6075);
FORCEPROP 1 LAST WATTAGE 1/16W
J 0
(-6760 5975);
DISPLAY 0.510638 (-6760 5975);
FORCEPROP 1 LAST PACK_TYPE 0402LF
J 0
(-6760 5825);
DISPLAY 0.510638 (-6760 5825);
FORCEPROP 1 LAST TOLERANCE 1%
J 0
(-6755 6025);
DISPLAY 0.510638 (-6755 6025);
FORCEPROP 1 LAST MATERIAL CHIP
J 0
(-6760 5925);
DISPLAY 0.510638 (-6760 5925);
FORCEPROP 2 LAST CDS_LIB pure_quanta
J 0
(-6800 6000);
DISPLAY INVISIBLE (-6800 6000);
FORCEPROP 1 LAST PATH I194
J 0
(-6750 6175);
DISPLAY 0.978723 (-6750 6175);
PAINT WHITE (-6750 6175);
DISPLAY INVISIBLE (-6750 6175);
FORCEPROP 1 LAST PART_NUMBER CS25112FB04
J 0
(-6760 5875);
DISPLAY 0.510638 (-6760 5875);
DISPLAY INVISIBLE (-6760 5875);
FORCEADD UNIVERSAL_POWER..1
(-6800 6250);
FORCEPROP 3 LASTPIN (-6800 6200) SIG_NAME P1V8_CPU1_RT_1D\g
J 0
(-6790 6210);
DISPLAY 0.659574 (-6790 6210);
PAINT MONO (-6790 6210);
DISPLAY INVISIBLE (-6790 6210);
FORCEPROP 1 LAST HDL_POWER P1V8_CPU1_RT_1D
J 1
(-6800 6300);
DISPLAY 0.872340 (-6800 6300);
PAINT GREEN (-6800 6300);
FORCEPROP 2 LAST CDS_LIB pure_quanta_power
J 0
(-6800 6250);
DISPLAY INVISIBLE (-6800 6250);
FORCEPROP 1 LAST PATH I195
J 0
(-6750 6275);
DISPLAY 0.872340 (-6750 6275);
PAINT AQUA (-6750 6275);
DISPLAY INVISIBLE (-6750 6275);
FORCEADD OFFPAGE..2
(-4850 5750);
FORCEPROP 2 LAST $XR0 259 
J 0
(-4661 5750);
DISPLAY 0.638298 (-4661 5750);
PAINT MONO (-4661 5750);
FORCEPROP 2 LAST CDS_LIB standard
J 0
(-4850 5750);
DISPLAY INVISIBLE (-4850 5750);
FORCEPROP 1 LAST OFFPAGE TRUE
J 0
(-4525 5625);
DISPLAY 0.872340 (-4525 5625);
DISPLAY INVISIBLE (-4525 5625);
FORCEPROP 1 LAST COMMENT_BODY TRUE
J 0
(-4895 5655);
DISPLAY 0.872340 (-4895 5655);
PAINT GREEN (-4895 5655);
DISPLAY INVISIBLE (-4895 5655);
FORCEPROP 2 LAST PATH I196
J 0
(-4650 5800);
DISPLAY 0.680851 (-4650 5800);
DISPLAY INVISIBLE (-4650 5800);
FORCEADD OFFPAGE..2
(-4825 5600);
FORCEPROP 2 LAST $XR0 259 
J 0
(-4636 5600);
DISPLAY 0.638298 (-4636 5600);
PAINT MONO (-4636 5600);
FORCEPROP 2 LAST CDS_LIB standard
J 0
(-4825 5600);
DISPLAY INVISIBLE (-4825 5600);
FORCEPROP 1 LAST OFFPAGE TRUE
J 0
(-4500 5475);
DISPLAY 0.872340 (-4500 5475);
DISPLAY INVISIBLE (-4500 5475);
FORCEPROP 1 LAST COMMENT_BODY TRUE
J 0
(-4870 5505);
DISPLAY 0.872340 (-4870 5505);
PAINT GREEN (-4870 5505);
DISPLAY INVISIBLE (-4870 5505);
FORCEPROP 2 LAST PATH I197
J 0
(-4625 5650);
DISPLAY 0.680851 (-4625 5650);
DISPLAY INVISIBLE (-4625 5650);
FORCEADD Q_CAP..1
(-4950 5375);
FORCEPROP 1 LAST LOCATION C1083
J 0
(-4900 5475);
DISPLAY 0.510638 (-4900 5475);
FORCEPROP 2 LAST $SEC 1
J 0
(-4900 5575);
DISPLAY 0.680851 (-4900 5575);
PAINT MONO (-4900 5575);
DISPLAY INVISIBLE (-4900 5575);
FORCEPROP 0 LAST CDS_SEC 1
J 0
(-4900 5550);
DISPLAY 1.021277 (-4900 5550);
DISPLAY INVISIBLE (-4900 5550);
FORCEPROP 1 LASTPIN (-4950 5475) $PN 1
J 0
(-4940 5455);
DISPLAY 0.787234 (-4940 5455);
PAINT MONO (-4940 5455);
FORCEPROP 1 LASTPIN (-4950 5275) $PN 2
J 0
(-4940 5255);
DISPLAY 0.787234 (-4940 5255);
PAINT MONO (-4940 5255);
FORCEPROP 1 LAST TOLERANCE 5%
J 0
(-4900 5325);
DISPLAY 0.510638 (-4900 5325);
FORCEPROP 1 LAST VALUE 100PF
J 0
(-4900 5425);
DISPLAY 0.510638 (-4900 5425);
FORCEPROP 1 LAST VOLTAGE 50V
J 0
(-4900 5375);
DISPLAY 0.510638 (-4900 5375);
FORCEPROP 1 LAST PACK_TYPE 0402
J 0
(-4900 5175);
DISPLAY 0.510638 (-4900 5175);
FORCEPROP 1 LAST MATERIAL EMPTY
J 0
(-4900 5275);
DISPLAY 0.510638 (-4900 5275);
FORCEPROP 0 LAST ROOM ADC_MAM_BOM2
J 0
(-4900 5525);
DISPLAY 0.553191 (-4900 5525);
PAINT RED (-4900 5525);
FORCEPROP 2 LAST CDS_LIB pure_quanta
J 0
(-4950 5375);
DISPLAY INVISIBLE (-4950 5375);
FORCEPROP 1 LAST PATH I198
J 0
(-4900 5525);
DISPLAY 0.978723 (-4900 5525);
PAINT WHITE (-4900 5525);
DISPLAY INVISIBLE (-4900 5525);
FORCEPROP 1 LAST PART_NUMBER CH11006JB18
J 0
(-4900 5225);
DISPLAY 0.510638 (-4900 5225);
DISPLAY INVISIBLE (-4900 5225);
FORCEADD UNIVERSAL_GND..1
(-4950 5100);
FORCEPROP 3 LASTPIN (-4950 5150) SIG_NAME GND\g
J 0
(-4940 5160);
DISPLAY 0.659574 (-4940 5160);
PAINT MONO (-4940 5160);
DISPLAY INVISIBLE (-4940 5160);
FORCEPROP 2 LAST CDS_LIB pure_quanta_power
J 0
(-4950 5100);
DISPLAY INVISIBLE (-4950 5100);
FORCEPROP 1 LAST HDL_POWER GND
J 1
(-4925 5025);
DISPLAY 0.872340 (-4925 5025);
PAINT GREEN (-4925 5025);
DISPLAY INVISIBLE (-4925 5025);
FORCEPROP 1 LAST PATH I199
J 0
(-4875 5100);
DISPLAY 0.872340 (-4875 5100);
PAINT AQUA (-4875 5100);
DISPLAY INVISIBLE (-4875 5100);
FORCEADD UNIVERSAL_POWER..1
(-8975 4950);
FORCEPROP 3 LASTPIN (-8975 4900) SIG_NAME P1V8_AUX\g
J 0
(-8965 4910);
DISPLAY 0.659574 (-8965 4910);
PAINT MONO (-8965 4910);
DISPLAY INVISIBLE (-8965 4910);
FORCEPROP 1 LAST HDL_POWER P1V8_AUX
J 1
(-8975 5000);
DISPLAY 0.872340 (-8975 5000);
PAINT GREEN (-8975 5000);
FORCEPROP 2 LAST CDS_LIB pure_quanta_power
J 0
(-8975 4950);
DISPLAY INVISIBLE (-8975 4950);
FORCEPROP 1 LAST PATH I20
J 0
(-8925 4975);
DISPLAY 0.872340 (-8925 4975);
PAINT AQUA (-8925 4975);
DISPLAY INVISIBLE (-8925 4975);
FORCEADD Q_CAP..1
R 2
(-5550 5350);
FORCEPROP 1 LAST LOCATION C1091
J 2
(-5375 5450);
DISPLAY 0.638298 (-5375 5450);
FORCEPROP 0 LAST $SEC 1
J 0
(-5450 5500);
DISPLAY 0.680851 (-5450 5500);
PAINT MONO (-5450 5500);
DISPLAY INVISIBLE (-5450 5500);
FORCEPROP 0 LAST CDS_SEC 1
J 0
(-5450 5500);
DISPLAY 1.021277 (-5450 5500);
DISPLAY INVISIBLE (-5450 5500);
FORCEPROP 1 LASTPIN (-5550 5450) $PN 1
J 2
(-5560 5430);
DISPLAY 0.787234 (-5560 5430);
PAINT MONO (-5560 5430);
FORCEPROP 1 LASTPIN (-5550 5250) $PN 2
J 2
(-5560 5230);
DISPLAY 0.787234 (-5560 5230);
PAINT MONO (-5560 5230);
FORCEPROP 1 LAST VOLTAGE 25V
J 2
(-5400 5375);
DISPLAY 0.510638 (-5400 5375);
FORCEPROP 1 LAST VALUE 0.1UF
J 2
(-5375 5425);
DISPLAY 0.510638 (-5375 5425);
FORCEPROP 0 LAST ROOM ADC_TI_BOM1
J 0
(-5475 5500);
DISPLAY 0.680851 (-5475 5500);
PAINT RED (-5475 5500);
FORCEPROP 1 LAST TOLERANCE 10%
J 2
(-5400 5325);
DISPLAY 0.510638 (-5400 5325);
FORCEPROP 1 LAST PACK_TYPE 0402
J 2
(-5375 5175);
DISPLAY 0.510638 (-5375 5175);
FORCEPROP 1 LAST MATERIAL X7R
J 2
(-5400 5275);
DISPLAY 0.510638 (-5400 5275);
PAINT RED (-5400 5275);
FORCEPROP 2 LAST CDS_LIB pure_quanta
J 0
(-5550 5350);
DISPLAY INVISIBLE (-5550 5350);
FORCEPROP 1 LAST PATH I200
J 2
(-5600 5500);
DISPLAY 0.978723 (-5600 5500);
PAINT WHITE (-5600 5500);
DISPLAY INVISIBLE (-5600 5500);
FORCEPROP 1 LAST PART_NUMBER CH4104K1B00
J 2
(-5250 5225);
DISPLAY 0.510638 (-5250 5225);
DISPLAY INVISIBLE (-5250 5225);
FORCEADD UNIVERSAL_GND..1
(-5550 5075);
FORCEPROP 3 LASTPIN (-5550 5125) SIG_NAME GND\g
J 0
(-5540 5135);
DISPLAY 0.659574 (-5540 5135);
PAINT MONO (-5540 5135);
DISPLAY INVISIBLE (-5540 5135);
FORCEPROP 2 LAST CDS_LIB pure_quanta_power
J 0
(-5550 5075);
DISPLAY INVISIBLE (-5550 5075);
FORCEPROP 1 LAST HDL_POWER GND
J 1
(-5525 5000);
DISPLAY 0.872340 (-5525 5000);
PAINT GREEN (-5525 5000);
DISPLAY INVISIBLE (-5525 5000);
FORCEPROP 1 LAST PATH I201
J 0
(-5475 5075);
DISPLAY 0.872340 (-5475 5075);
PAINT AQUA (-5475 5075);
DISPLAY INVISIBLE (-5475 5075);
FORCEADD Q_RES..1
(-5925 5750);
FORCEPROP 1 LAST LOCATION R1250
J 0
(-6125 5750);
DISPLAY 0.510638 (-6125 5750);
FORCEPROP 0 LAST $SEC 1
J 0
(-6050 5800);
DISPLAY 0.680851 (-6050 5800);
PAINT MONO (-6050 5800);
DISPLAY INVISIBLE (-6050 5800);
FORCEPROP 0 LAST CDS_SEC 1
J 0
(-6050 5800);
DISPLAY 1.021277 (-6050 5800);
DISPLAY INVISIBLE (-6050 5800);
FORCEPROP 1 LASTPIN (-6025 5750) $PN 1
J 0
(-6013 5762);
DISPLAY 0.787234 (-6013 5762);
PAINT MONO (-6013 5762);
FORCEPROP 1 LASTPIN (-5825 5750) $PN 2
J 0
(-5863 5762);
DISPLAY 0.787234 (-5863 5762);
PAINT MONO (-5863 5762);
FORCEPROP 1 LAST MATERIAL EMPTY
J 0
(-5700 5750);
DISPLAY 0.404255 (-5700 5750);
FORCEPROP 1 LAST TOLERANCE 5%
J 0
(-5750 5750);
DISPLAY 0.404255 (-5750 5750);
FORCEPROP 1 LAST VALUE 0
J 2
(-5775 5750);
DISPLAY 0.404255 (-5775 5750);
FORCEPROP 0 LAST ROOM ADC_MAM_BOM2
J 0
(-6075 5875);
DISPLAY 0.553191 (-6075 5875);
PAINT RED (-6075 5875);
FORCEPROP 1 LAST PACK_TYPE 0402LF
J 0
(-5675 5750);
DISPLAY 0.510638 (-5675 5750);
DISPLAY INVISIBLE (-5675 5750);
FORCEPROP 1 LAST WATTAGE 1/16W
J 2
(-5825 5675);
DISPLAY 0.319149 (-5825 5675);
DISPLAY INVISIBLE (-5825 5675);
FORCEPROP 2 LAST CDS_LIB pure_quanta
J 0
(-5925 5750);
DISPLAY INVISIBLE (-5925 5750);
FORCEPROP 1 LAST PATH I202
J 0
(-5975 5900);
DISPLAY 0.978723 (-5975 5900);
PAINT WHITE (-5975 5900);
DISPLAY INVISIBLE (-5975 5900);
FORCEPROP 1 LAST PART_NUMBER CS00002JB13
J 0
(-6000 5700);
DISPLAY 0.319149 (-6000 5700);
DISPLAY INVISIBLE (-6000 5700);
FORCEADD Q_RES..1
(-5925 5600);
FORCEPROP 1 LAST LOCATION R1257
J 0
(-6125 5600);
DISPLAY 0.510638 (-6125 5600);
FORCEPROP 0 LAST $SEC 1
J 0
(-6050 5650);
DISPLAY 0.680851 (-6050 5650);
PAINT MONO (-6050 5650);
DISPLAY INVISIBLE (-6050 5650);
FORCEPROP 0 LAST CDS_SEC 1
J 0
(-6050 5650);
DISPLAY 1.021277 (-6050 5650);
DISPLAY INVISIBLE (-6050 5650);
FORCEPROP 1 LASTPIN (-6025 5600) $PN 1
J 0
(-6013 5612);
DISPLAY 0.787234 (-6013 5612);
PAINT MONO (-6013 5612);
FORCEPROP 1 LASTPIN (-5825 5600) $PN 2
J 0
(-5863 5612);
DISPLAY 0.787234 (-5863 5612);
PAINT MONO (-5863 5612);
FORCEPROP 1 LAST TOLERANCE 5%
J 0
(-5750 5600);
DISPLAY 0.404255 (-5750 5600);
FORCEPROP 1 LAST VALUE 0
J 2
(-5775 5600);
DISPLAY 0.404255 (-5775 5600);
FORCEPROP 1 LAST MATERIAL CHIP
J 0
(-5700 5600);
DISPLAY 0.404255 (-5700 5600);
PAINT RED (-5700 5600);
FORCEPROP 0 LAST ROOM ADC_TI_BOM1
J 0
(-6100 5525);
DISPLAY 0.680851 (-6100 5525);
PAINT RED (-6100 5525);
FORCEPROP 2 LAST CDS_LIB pure_quanta
J 0
(-5925 5600);
DISPLAY INVISIBLE (-5925 5600);
FORCEPROP 1 LAST WATTAGE 1/16W
J 2
(-5825 5525);
DISPLAY 0.319149 (-5825 5525);
DISPLAY INVISIBLE (-5825 5525);
FORCEPROP 1 LAST PACK_TYPE 0402LF
J 0
(-5675 5600);
DISPLAY 0.510638 (-5675 5600);
DISPLAY INVISIBLE (-5675 5600);
FORCEPROP 1 LAST PATH I203
J 0
(-5975 5750);
DISPLAY 0.978723 (-5975 5750);
PAINT WHITE (-5975 5750);
DISPLAY INVISIBLE (-5975 5750);
FORCEPROP 1 LAST PART_NUMBER CS00002JB13
J 0
(-6000 5550);
DISPLAY 0.319149 (-6000 5550);
DISPLAY INVISIBLE (-6000 5550);
FORCEADD UNIVERSAL_GND..1
(-6800 5150);
FORCEPROP 3 LASTPIN (-6800 5200) SIG_NAME GND\g
J 0
(-6790 5210);
DISPLAY 0.659574 (-6790 5210);
PAINT MONO (-6790 5210);
DISPLAY INVISIBLE (-6790 5210);
FORCEPROP 2 LAST CDS_LIB pure_quanta_power
J 0
(-6800 5150);
DISPLAY INVISIBLE (-6800 5150);
FORCEPROP 1 LAST HDL_POWER GND
J 1
(-6775 5075);
DISPLAY 0.872340 (-6775 5075);
PAINT GREEN (-6775 5075);
DISPLAY INVISIBLE (-6775 5075);
FORCEPROP 1 LAST PATH I205
J 0
(-6725 5150);
DISPLAY 0.872340 (-6725 5150);
PAINT AQUA (-6725 5150);
DISPLAY INVISIBLE (-6725 5150);
FORCEADD OFFPAGE..2
(-5100 4075);
FORCEPROP 2 LAST $XR0 259 
J 0
(-4911 4075);
DISPLAY 0.638298 (-4911 4075);
PAINT MONO (-4911 4075);
FORCEPROP 2 LAST CDS_LIB standard
J 0
(-5100 4075);
DISPLAY INVISIBLE (-5100 4075);
FORCEPROP 1 LAST OFFPAGE TRUE
J 0
(-4775 3950);
DISPLAY 0.872340 (-4775 3950);
DISPLAY INVISIBLE (-4775 3950);
FORCEPROP 1 LAST COMMENT_BODY TRUE
J 0
(-5145 3980);
DISPLAY 0.872340 (-5145 3980);
PAINT GREEN (-5145 3980);
DISPLAY INVISIBLE (-5145 3980);
FORCEPROP 2 LAST PATH I206
J 0
(-4900 4125);
DISPLAY 0.680851 (-4900 4125);
DISPLAY INVISIBLE (-4900 4125);
FORCEADD UNIVERSAL_POWER..1
(-6750 4725);
FORCEPROP 3 LASTPIN (-6750 4675) SIG_NAME PVDD_33_S5\g
J 0
(-6740 4685);
DISPLAY 0.659574 (-6740 4685);
PAINT MONO (-6740 4685);
DISPLAY INVISIBLE (-6740 4685);
FORCEPROP 1 LAST HDL_POWER PVDD_33_S5
J 1
(-6750 4775);
DISPLAY 0.872340 (-6750 4775);
PAINT GREEN (-6750 4775);
FORCEPROP 2 LAST CDS_LIB pure_quanta_power
J 0
(-6750 4725);
DISPLAY INVISIBLE (-6750 4725);
FORCEPROP 1 LAST PATH I207
J 0
(-6700 4750);
DISPLAY 0.872340 (-6700 4750);
PAINT AQUA (-6700 4750);
DISPLAY INVISIBLE (-6700 4750);
FORCEADD OFFPAGE..2
(-5100 4225);
FORCEPROP 2 LAST $XR0 259 
J 0
(-4911 4225);
DISPLAY 0.638298 (-4911 4225);
PAINT MONO (-4911 4225);
FORCEPROP 2 LAST CDS_LIB standard
J 0
(-5100 4225);
DISPLAY INVISIBLE (-5100 4225);
FORCEPROP 1 LAST OFFPAGE TRUE
J 0
(-4775 4100);
DISPLAY 0.872340 (-4775 4100);
DISPLAY INVISIBLE (-4775 4100);
FORCEPROP 1 LAST COMMENT_BODY TRUE
J 0
(-5145 4130);
DISPLAY 0.872340 (-5145 4130);
PAINT GREEN (-5145 4130);
DISPLAY INVISIBLE (-5145 4130);
FORCEPROP 2 LAST PATH I208
J 0
(-4900 4275);
DISPLAY 0.680851 (-4900 4275);
DISPLAY INVISIBLE (-4900 4275);
FORCEADD Q_CAP..1
(-5200 3825);
FORCEPROP 1 LAST LOCATION C1082
J 0
(-5150 3925);
DISPLAY 0.510638 (-5150 3925);
FORCEPROP 2 LAST $SEC 1
J 0
(-5150 4025);
DISPLAY 0.680851 (-5150 4025);
PAINT MONO (-5150 4025);
DISPLAY INVISIBLE (-5150 4025);
FORCEPROP 0 LAST CDS_SEC 1
J 0
(-5150 4000);
DISPLAY 1.021277 (-5150 4000);
DISPLAY INVISIBLE (-5150 4000);
FORCEPROP 1 LASTPIN (-5200 3925) $PN 1
J 0
(-5190 3905);
DISPLAY 0.787234 (-5190 3905);
PAINT MONO (-5190 3905);
FORCEPROP 1 LASTPIN (-5200 3725) $PN 2
J 0
(-5190 3705);
DISPLAY 0.787234 (-5190 3705);
PAINT MONO (-5190 3705);
FORCEPROP 1 LAST MATERIAL EMPTY
J 0
(-5150 3725);
DISPLAY 0.510638 (-5150 3725);
FORCEPROP 1 LAST PACK_TYPE 0402
J 0
(-5150 3625);
DISPLAY 0.510638 (-5150 3625);
FORCEPROP 1 LAST TOLERANCE 5%
J 0
(-5150 3775);
DISPLAY 0.510638 (-5150 3775);
FORCEPROP 1 LAST VOLTAGE 50V
J 0
(-5150 3825);
DISPLAY 0.510638 (-5150 3825);
FORCEPROP 1 LAST VALUE 100PF
J 0
(-5150 3875);
DISPLAY 0.510638 (-5150 3875);
FORCEPROP 0 LAST ROOM ADC_MAM_BOM2
J 0
(-5150 3975);
DISPLAY 0.680851 (-5150 3975);
PAINT RED (-5150 3975);
FORCEPROP 2 LAST CDS_LIB pure_quanta
J 0
(-5200 3825);
DISPLAY INVISIBLE (-5200 3825);
FORCEPROP 1 LAST PATH I209
J 0
(-5150 3975);
DISPLAY 0.978723 (-5150 3975);
PAINT WHITE (-5150 3975);
DISPLAY INVISIBLE (-5150 3975);
FORCEPROP 1 LAST PART_NUMBER CH11006JB18
J 0
(-5150 3675);
DISPLAY 0.510638 (-5150 3675);
DISPLAY INVISIBLE (-5150 3675);
FORCEADD Q_RES..1
(-8350 4300);
FORCEPROP 1 LAST LOCATION R1259
J 0
(-8550 4300);
DISPLAY 0.510638 (-8550 4300);
FORCEPROP 0 LAST $SEC 1
J 0
(-8475 4350);
DISPLAY 0.680851 (-8475 4350);
PAINT MONO (-8475 4350);
DISPLAY INVISIBLE (-8475 4350);
FORCEPROP 0 LAST CDS_SEC 1
J 0
(-8475 4350);
DISPLAY 1.021277 (-8475 4350);
DISPLAY INVISIBLE (-8475 4350);
FORCEPROP 1 LASTPIN (-8450 4300) $PN 1
J 0
(-8438 4312);
DISPLAY 0.787234 (-8438 4312);
PAINT MONO (-8438 4312);
FORCEPROP 1 LASTPIN (-8250 4300) $PN 2
J 0
(-8288 4312);
DISPLAY 0.787234 (-8288 4312);
PAINT MONO (-8288 4312);
FORCEPROP 0 LAST ROOM ADC_TI_BOM1
J 0
(-8500 4225);
DISPLAY 0.680851 (-8500 4225);
PAINT RED (-8500 4225);
FORCEPROP 1 LAST TOLERANCE 5%
J 0
(-8175 4300);
DISPLAY 0.404255 (-8175 4300);
FORCEPROP 1 LAST MATERIAL CHIP
J 0
(-8125 4300);
DISPLAY 0.404255 (-8125 4300);
PAINT RED (-8125 4300);
FORCEPROP 1 LAST VALUE 0
J 2
(-8200 4300);
DISPLAY 0.404255 (-8200 4300);
FORCEPROP 2 LAST CDS_LIB pure_quanta
J 0
(-8350 4300);
DISPLAY INVISIBLE (-8350 4300);
FORCEPROP 1 LAST WATTAGE 1/16W
J 2
(-8250 4225);
DISPLAY 0.319149 (-8250 4225);
DISPLAY INVISIBLE (-8250 4225);
FORCEPROP 1 LAST PACK_TYPE 0402LF
J 0
(-8100 4300);
DISPLAY 0.510638 (-8100 4300);
DISPLAY INVISIBLE (-8100 4300);
FORCEPROP 1 LAST PATH I21
J 0
(-8400 4450);
DISPLAY 0.978723 (-8400 4450);
PAINT WHITE (-8400 4450);
DISPLAY INVISIBLE (-8400 4450);
FORCEPROP 1 LAST PART_NUMBER CS00002JB13
J 0
(-8425 4250);
DISPLAY 0.319149 (-8425 4250);
DISPLAY INVISIBLE (-8425 4250);
FORCEADD UNIVERSAL_GND..1
(-5200 3550);
FORCEPROP 3 LASTPIN (-5200 3600) SIG_NAME GND\g
J 0
(-5190 3610);
DISPLAY 0.659574 (-5190 3610);
PAINT MONO (-5190 3610);
DISPLAY INVISIBLE (-5190 3610);
FORCEPROP 2 LAST CDS_LIB pure_quanta_power
J 0
(-5200 3550);
DISPLAY INVISIBLE (-5200 3550);
FORCEPROP 1 LAST HDL_POWER GND
J 1
(-5175 3475);
DISPLAY 0.872340 (-5175 3475);
PAINT GREEN (-5175 3475);
DISPLAY INVISIBLE (-5175 3475);
FORCEPROP 1 LAST PATH I210
J 0
(-5125 3550);
DISPLAY 0.872340 (-5125 3550);
PAINT AQUA (-5125 3550);
DISPLAY INVISIBLE (-5125 3550);
FORCEADD Q_CAP..1
R 2
(-5675 3825);
FORCEPROP 1 LAST LOCATION C1089
J 2
(-5500 3925);
DISPLAY 0.638298 (-5500 3925);
FORCEPROP 0 LAST $SEC 1
J 0
(-5575 3975);
DISPLAY 0.680851 (-5575 3975);
PAINT MONO (-5575 3975);
DISPLAY INVISIBLE (-5575 3975);
FORCEPROP 0 LAST CDS_SEC 1
J 0
(-5575 3975);
DISPLAY 1.021277 (-5575 3975);
DISPLAY INVISIBLE (-5575 3975);
FORCEPROP 1 LASTPIN (-5675 3925) $PN 1
J 2
(-5685 3905);
DISPLAY 0.787234 (-5685 3905);
PAINT MONO (-5685 3905);
FORCEPROP 1 LASTPIN (-5675 3725) $PN 2
J 2
(-5685 3705);
DISPLAY 0.787234 (-5685 3705);
PAINT MONO (-5685 3705);
FORCEPROP 1 LAST MATERIAL X7R
J 2
(-5525 3750);
DISPLAY 0.510638 (-5525 3750);
PAINT RED (-5525 3750);
FORCEPROP 1 LAST TOLERANCE 10%
J 2
(-5525 3800);
DISPLAY 0.510638 (-5525 3800);
FORCEPROP 1 LAST VALUE 0.1UF
J 2
(-5500 3900);
DISPLAY 0.510638 (-5500 3900);
FORCEPROP 0 LAST ROOM ADC_TI_BOM1
J 0
(-5625 3975);
DISPLAY 0.553191 (-5625 3975);
PAINT RED (-5625 3975);
FORCEPROP 1 LAST PACK_TYPE 0402
J 2
(-5500 3650);
DISPLAY 0.510638 (-5500 3650);
FORCEPROP 1 LAST VOLTAGE 25V
J 2
(-5525 3850);
DISPLAY 0.510638 (-5525 3850);
FORCEPROP 2 LAST CDS_LIB pure_quanta
J 0
(-5675 3825);
DISPLAY INVISIBLE (-5675 3825);
FORCEPROP 1 LAST PATH I211
J 2
(-5725 3975);
DISPLAY 0.978723 (-5725 3975);
PAINT WHITE (-5725 3975);
DISPLAY INVISIBLE (-5725 3975);
FORCEPROP 1 LAST PART_NUMBER CH4104K1B00
J 2
(-5375 3700);
DISPLAY 0.510638 (-5375 3700);
DISPLAY INVISIBLE (-5375 3700);
FORCEADD UNIVERSAL_GND..1
(-5675 3550);
FORCEPROP 3 LASTPIN (-5675 3600) SIG_NAME GND\g
J 0
(-5665 3610);
DISPLAY 0.659574 (-5665 3610);
PAINT MONO (-5665 3610);
DISPLAY INVISIBLE (-5665 3610);
FORCEPROP 2 LAST CDS_LIB pure_quanta_power
J 0
(-5675 3550);
DISPLAY INVISIBLE (-5675 3550);
FORCEPROP 1 LAST HDL_POWER GND
J 1
(-5650 3475);
DISPLAY 0.872340 (-5650 3475);
PAINT GREEN (-5650 3475);
DISPLAY INVISIBLE (-5650 3475);
FORCEPROP 1 LAST PATH I212
J 0
(-5600 3550);
DISPLAY 0.872340 (-5600 3550);
PAINT AQUA (-5600 3550);
DISPLAY INVISIBLE (-5600 3550);
FORCEADD Q_RES..1
(-6050 4225);
FORCEPROP 1 LAST LOCATION R1248
J 0
(-6250 4225);
DISPLAY 0.510638 (-6250 4225);
FORCEPROP 0 LAST $SEC 1
J 0
(-6175 4275);
DISPLAY 0.680851 (-6175 4275);
PAINT MONO (-6175 4275);
DISPLAY INVISIBLE (-6175 4275);
FORCEPROP 0 LAST CDS_SEC 1
J 0
(-6175 4275);
DISPLAY 1.021277 (-6175 4275);
DISPLAY INVISIBLE (-6175 4275);
FORCEPROP 1 LASTPIN (-6150 4225) $PN 1
J 0
(-6138 4237);
DISPLAY 0.787234 (-6138 4237);
PAINT MONO (-6138 4237);
FORCEPROP 1 LASTPIN (-5950 4225) $PN 2
J 0
(-5988 4237);
DISPLAY 0.787234 (-5988 4237);
PAINT MONO (-5988 4237);
FORCEPROP 1 LAST VALUE 0
J 2
(-5900 4225);
DISPLAY 0.404255 (-5900 4225);
FORCEPROP 1 LAST MATERIAL EMPTY
J 0
(-5825 4225);
DISPLAY 0.404255 (-5825 4225);
FORCEPROP 1 LAST TOLERANCE 5%
J 0
(-5875 4225);
DISPLAY 0.404255 (-5875 4225);
FORCEPROP 0 LAST ROOM ADC_MAM_BOM2
J 0
(-6175 4350);
DISPLAY 0.680851 (-6175 4350);
PAINT RED (-6175 4350);
FORCEPROP 1 LAST PACK_TYPE 0402LF
J 0
(-5800 4225);
DISPLAY 0.510638 (-5800 4225);
DISPLAY INVISIBLE (-5800 4225);
FORCEPROP 1 LAST WATTAGE 1/16W
J 2
(-5950 4150);
DISPLAY 0.319149 (-5950 4150);
DISPLAY INVISIBLE (-5950 4150);
FORCEPROP 2 LAST CDS_LIB pure_quanta
J 0
(-6050 4225);
DISPLAY INVISIBLE (-6050 4225);
FORCEPROP 1 LAST PATH I213
J 0
(-6100 4375);
DISPLAY 0.978723 (-6100 4375);
PAINT WHITE (-6100 4375);
DISPLAY INVISIBLE (-6100 4375);
FORCEPROP 1 LAST PART_NUMBER CS00002JB13
J 0
(-6125 4175);
DISPLAY 0.319149 (-6125 4175);
DISPLAY INVISIBLE (-6125 4175);
FORCEADD Q_RES..1
(-6050 4075);
FORCEPROP 1 LAST LOCATION R1255
J 0
(-6250 4075);
DISPLAY 0.510638 (-6250 4075);
FORCEPROP 0 LAST $SEC 1
J 0
(-6175 4125);
DISPLAY 0.680851 (-6175 4125);
PAINT MONO (-6175 4125);
DISPLAY INVISIBLE (-6175 4125);
FORCEPROP 0 LAST CDS_SEC 1
J 0
(-6175 4125);
DISPLAY 1.021277 (-6175 4125);
DISPLAY INVISIBLE (-6175 4125);
FORCEPROP 1 LASTPIN (-6150 4075) $PN 1
J 0
(-6138 4087);
DISPLAY 0.787234 (-6138 4087);
PAINT MONO (-6138 4087);
FORCEPROP 1 LASTPIN (-5950 4075) $PN 2
J 0
(-5988 4087);
DISPLAY 0.787234 (-5988 4087);
PAINT MONO (-5988 4087);
FORCEPROP 0 LAST ROOM ADC_TI_BOM1
J 0
(-6225 4025);
DISPLAY 0.680851 (-6225 4025);
PAINT RED (-6225 4025);
FORCEPROP 1 LAST TOLERANCE 5%
J 0
(-5875 4075);
DISPLAY 0.404255 (-5875 4075);
FORCEPROP 1 LAST MATERIAL CHIP
J 0
(-5825 4075);
DISPLAY 0.404255 (-5825 4075);
PAINT RED (-5825 4075);
FORCEPROP 1 LAST VALUE 0
J 2
(-5900 4075);
DISPLAY 0.404255 (-5900 4075);
FORCEPROP 1 LAST PACK_TYPE 0402LF
J 0
(-5800 4075);
DISPLAY 0.510638 (-5800 4075);
DISPLAY INVISIBLE (-5800 4075);
FORCEPROP 1 LAST WATTAGE 1/16W
J 2
(-5950 4000);
DISPLAY 0.319149 (-5950 4000);
DISPLAY INVISIBLE (-5950 4000);
FORCEPROP 2 LAST CDS_LIB pure_quanta
J 0
(-6050 4075);
DISPLAY INVISIBLE (-6050 4075);
FORCEPROP 1 LAST PATH I214
J 0
(-6100 4225);
DISPLAY 0.978723 (-6100 4225);
PAINT WHITE (-6100 4225);
DISPLAY INVISIBLE (-6100 4225);
FORCEPROP 1 LAST PART_NUMBER CS00002JB13
J 0
(-6125 4025);
DISPLAY 0.319149 (-6125 4025);
DISPLAY INVISIBLE (-6125 4025);
FORCEADD Q_RES..2
(-6750 4475);
FORCEPROP 1 LAST LOCATION R1235
J 0
(-6705 4600);
DISPLAY 0.510638 (-6705 4600);
FORCEPROP 2 LAST $SEC 1
J 0
(-6700 4700);
DISPLAY 0.680851 (-6700 4700);
PAINT MONO (-6700 4700);
DISPLAY INVISIBLE (-6700 4700);
FORCEPROP 2 LAST CDS_SEC 1
J 0
(-6700 4700);
DISPLAY 1.021277 (-6700 4700);
DISPLAY INVISIBLE (-6700 4700);
FORCEPROP 1 LASTPIN (-6750 4575) $PN 1
J 0
(-6745 4537);
DISPLAY 0.787234 (-6745 4537);
PAINT MONO (-6745 4537);
FORCEPROP 1 LASTPIN (-6750 4375) $PN 2
J 0
(-6745 4385);
DISPLAY 0.787234 (-6745 4385);
PAINT MONO (-6745 4385);
FORCEPROP 1 LAST TOLERANCE 1%
J 0
(-6705 4500);
DISPLAY 0.510638 (-6705 4500);
FORCEPROP 1 LAST VALUE 5.11K
J 0
(-6705 4550);
DISPLAY 0.510638 (-6705 4550);
FORCEPROP 1 LAST MATERIAL CHIP
J 0
(-6710 4400);
DISPLAY 0.510638 (-6710 4400);
FORCEPROP 1 LAST PACK_TYPE 0402LF
J 0
(-6710 4300);
DISPLAY 0.510638 (-6710 4300);
FORCEPROP 1 LAST WATTAGE 1/16W
J 0
(-6710 4450);
DISPLAY 0.510638 (-6710 4450);
FORCEPROP 2 LAST CDS_LIB pure_quanta
J 0
(-6750 4475);
DISPLAY INVISIBLE (-6750 4475);
FORCEPROP 1 LAST PATH I215
J 0
(-6700 4650);
DISPLAY 0.978723 (-6700 4650);
PAINT WHITE (-6700 4650);
DISPLAY INVISIBLE (-6700 4650);
FORCEPROP 1 LAST PART_NUMBER CS25112FB04
J 0
(-6710 4350);
DISPLAY 0.510638 (-6710 4350);
DISPLAY INVISIBLE (-6710 4350);
FORCEADD Q_RES..2
(-6750 3950);
FORCEPROP 1 LAST LOCATION R1224
J 0
(-6705 4075);
DISPLAY 0.638298 (-6705 4075);
FORCEPROP 0 LAST $SEC 1
J 0
(-6700 4125);
DISPLAY 0.680851 (-6700 4125);
PAINT MONO (-6700 4125);
DISPLAY INVISIBLE (-6700 4125);
FORCEPROP 0 LAST CDS_SEC 1
J 0
(-6700 4125);
DISPLAY 1.021277 (-6700 4125);
DISPLAY INVISIBLE (-6700 4125);
FORCEPROP 1 LASTPIN (-6750 4050) $PN 1
J 0
(-6745 4012);
DISPLAY 0.787234 (-6745 4012);
PAINT MONO (-6745 4012);
FORCEPROP 1 LASTPIN (-6750 3850) $PN 2
J 0
(-6745 3860);
DISPLAY 0.787234 (-6745 3860);
PAINT MONO (-6745 3860);
FORCEPROP 1 LAST VALUE 4.7K
J 0
(-6705 4025);
DISPLAY 0.510638 (-6705 4025);
FORCEPROP 1 LAST TOLERANCE 1%
J 0
(-6705 3975);
DISPLAY 0.510638 (-6705 3975);
FORCEPROP 1 LAST MATERIAL CHIP
J 0
(-6710 3875);
DISPLAY 0.510638 (-6710 3875);
FORCEPROP 1 LAST WATTAGE 1/16W
J 0
(-6710 3925);
DISPLAY 0.510638 (-6710 3925);
FORCEPROP 1 LAST PACK_TYPE 0402LF
J 0
(-6710 3775);
DISPLAY 0.510638 (-6710 3775);
FORCEPROP 2 LAST CDS_LIB pure_quanta
J 0
(-6750 3950);
DISPLAY INVISIBLE (-6750 3950);
FORCEPROP 1 LAST PATH I216
J 0
(-6700 4125);
DISPLAY 0.978723 (-6700 4125);
PAINT WHITE (-6700 4125);
DISPLAY INVISIBLE (-6700 4125);
FORCEPROP 1 LAST PART_NUMBER CS24702FB06
J 0
(-6710 3825);
DISPLAY 0.510638 (-6710 3825);
DISPLAY INVISIBLE (-6710 3825);
FORCEADD UNIVERSAL_GND..1
(-6750 3600);
FORCEPROP 3 LASTPIN (-6750 3650) SIG_NAME GND\g
J 0
(-6740 3660);
DISPLAY 0.659574 (-6740 3660);
PAINT MONO (-6740 3660);
DISPLAY INVISIBLE (-6740 3660);
FORCEPROP 2 LAST CDS_LIB pure_quanta_power
J 0
(-6750 3600);
DISPLAY INVISIBLE (-6750 3600);
FORCEPROP 1 LAST HDL_POWER GND
J 1
(-6725 3525);
DISPLAY 0.872340 (-6725 3525);
PAINT GREEN (-6725 3525);
DISPLAY INVISIBLE (-6725 3525);
FORCEPROP 1 LAST PATH I217
J 0
(-6675 3600);
DISPLAY 0.872340 (-6675 3600);
PAINT AQUA (-6675 3600);
DISPLAY INVISIBLE (-6675 3600);
FORCEADD UNIVERSAL_POWER..1
(-6850 3300);
FORCEPROP 3 LASTPIN (-6850 3250) SIG_NAME PVDD18_S5_P0\g
J 0
(-6840 3260);
DISPLAY 0.659574 (-6840 3260);
PAINT MONO (-6840 3260);
DISPLAY INVISIBLE (-6840 3260);
FORCEPROP 1 LAST HDL_POWER PVDD18_S5_P0
J 1
(-6850 3350);
DISPLAY 0.872340 (-6850 3350);
PAINT GREEN (-6850 3350);
FORCEPROP 2 LAST CDS_LIB pure_quanta_power
J 0
(-6850 3300);
DISPLAY INVISIBLE (-6850 3300);
FORCEPROP 1 LAST PATH I218
J 0
(-6800 3325);
DISPLAY 0.872340 (-6800 3325);
PAINT AQUA (-6800 3325);
DISPLAY INVISIBLE (-6800 3325);
FORCEADD OFFPAGE..2
(-5300 2800);
FORCEPROP 2 LAST $XR0 259 
J 0
(-5111 2800);
DISPLAY 0.638298 (-5111 2800);
PAINT MONO (-5111 2800);
FORCEPROP 2 LAST CDS_LIB standard
J 0
(-5300 2800);
DISPLAY INVISIBLE (-5300 2800);
FORCEPROP 1 LAST OFFPAGE TRUE
J 0
(-4975 2675);
DISPLAY 0.872340 (-4975 2675);
DISPLAY INVISIBLE (-4975 2675);
FORCEPROP 1 LAST COMMENT_BODY TRUE
J 0
(-5345 2705);
DISPLAY 0.872340 (-5345 2705);
PAINT GREEN (-5345 2705);
DISPLAY INVISIBLE (-5345 2705);
FORCEPROP 2 LAST PATH I219
J 0
(-5100 2850);
DISPLAY 0.680851 (-5100 2850);
DISPLAY INVISIBLE (-5100 2850);
FORCEADD Q_RES..1
(-8350 4450);
FORCEPROP 1 LAST LOCATION R1258
J 0
(-8550 4450);
DISPLAY 0.510638 (-8550 4450);
FORCEPROP 0 LAST $SEC 1
J 0
(-8475 4500);
DISPLAY 0.680851 (-8475 4500);
PAINT MONO (-8475 4500);
DISPLAY INVISIBLE (-8475 4500);
FORCEPROP 0 LAST CDS_SEC 1
J 0
(-8475 4500);
DISPLAY 1.021277 (-8475 4500);
DISPLAY INVISIBLE (-8475 4500);
FORCEPROP 1 LASTPIN (-8450 4450) $PN 1
J 0
(-8438 4462);
DISPLAY 0.787234 (-8438 4462);
PAINT MONO (-8438 4462);
FORCEPROP 1 LASTPIN (-8250 4450) $PN 2
J 0
(-8288 4462);
DISPLAY 0.787234 (-8288 4462);
PAINT MONO (-8288 4462);
FORCEPROP 1 LAST TOLERANCE 5%
J 0
(-8175 4450);
DISPLAY 0.404255 (-8175 4450);
FORCEPROP 1 LAST VALUE 0
J 2
(-8200 4450);
DISPLAY 0.404255 (-8200 4450);
FORCEPROP 1 LAST MATERIAL EMPTY
J 0
(-8125 4450);
DISPLAY 0.404255 (-8125 4450);
FORCEPROP 0 LAST ROOM ADC_MAM_BOM2
J 0
(-8500 4550);
DISPLAY 0.680851 (-8500 4550);
PAINT RED (-8500 4550);
FORCEPROP 2 LAST CDS_LIB pure_quanta
J 0
(-8350 4450);
DISPLAY INVISIBLE (-8350 4450);
FORCEPROP 1 LAST WATTAGE 1/16W
J 2
(-8250 4375);
DISPLAY 0.319149 (-8250 4375);
DISPLAY INVISIBLE (-8250 4375);
FORCEPROP 1 LAST PACK_TYPE 0402LF
J 0
(-8100 4450);
DISPLAY 0.510638 (-8100 4450);
DISPLAY INVISIBLE (-8100 4450);
FORCEPROP 1 LAST PATH I22
J 0
(-8400 4600);
DISPLAY 0.978723 (-8400 4600);
PAINT WHITE (-8400 4600);
DISPLAY INVISIBLE (-8400 4600);
FORCEPROP 1 LAST PART_NUMBER CS00002JB13
J 0
(-8425 4400);
DISPLAY 0.319149 (-8425 4400);
DISPLAY INVISIBLE (-8425 4400);
FORCEADD OFFPAGE..2
(-5300 2650);
FORCEPROP 2 LAST $XR0 259 
J 0
(-5111 2650);
DISPLAY 0.638298 (-5111 2650);
PAINT MONO (-5111 2650);
FORCEPROP 2 LAST CDS_LIB standard
J 0
(-5300 2650);
DISPLAY INVISIBLE (-5300 2650);
FORCEPROP 1 LAST OFFPAGE TRUE
J 0
(-4975 2525);
DISPLAY 0.872340 (-4975 2525);
DISPLAY INVISIBLE (-4975 2525);
FORCEPROP 1 LAST COMMENT_BODY TRUE
J 0
(-5345 2555);
DISPLAY 0.872340 (-5345 2555);
PAINT GREEN (-5345 2555);
DISPLAY INVISIBLE (-5345 2555);
FORCEPROP 2 LAST PATH I220
J 0
(-5100 2700);
DISPLAY 0.680851 (-5100 2700);
DISPLAY INVISIBLE (-5100 2700);
FORCEADD Q_CAP..1
(-5425 2400);
FORCEPROP 1 LAST LOCATION C1080
J 0
(-5375 2500);
DISPLAY 0.510638 (-5375 2500);
FORCEPROP 2 LAST $SEC 1
J 0
(-5375 2600);
DISPLAY 0.680851 (-5375 2600);
PAINT MONO (-5375 2600);
DISPLAY INVISIBLE (-5375 2600);
FORCEPROP 0 LAST CDS_SEC 1
J 0
(-5375 2575);
DISPLAY 1.021277 (-5375 2575);
DISPLAY INVISIBLE (-5375 2575);
FORCEPROP 1 LASTPIN (-5425 2500) $PN 1
J 0
(-5415 2480);
DISPLAY 0.787234 (-5415 2480);
PAINT MONO (-5415 2480);
FORCEPROP 1 LASTPIN (-5425 2300) $PN 2
J 0
(-5415 2280);
DISPLAY 0.787234 (-5415 2280);
PAINT MONO (-5415 2280);
FORCEPROP 1 LAST TOLERANCE 5%
J 0
(-5375 2350);
DISPLAY 0.510638 (-5375 2350);
FORCEPROP 1 LAST VOLTAGE 50V
J 0
(-5375 2400);
DISPLAY 0.510638 (-5375 2400);
FORCEPROP 1 LAST VALUE 100PF
J 0
(-5375 2450);
DISPLAY 0.510638 (-5375 2450);
FORCEPROP 1 LAST PACK_TYPE 0402
J 0
(-5375 2200);
DISPLAY 0.510638 (-5375 2200);
FORCEPROP 1 LAST MATERIAL EMPTY
J 0
(-5375 2300);
DISPLAY 0.510638 (-5375 2300);
FORCEPROP 0 LAST ROOM ADC_MAM_BOM2
J 0
(-5375 2150);
DISPLAY 0.553191 (-5375 2150);
PAINT RED (-5375 2150);
FORCEPROP 2 LAST CDS_LIB pure_quanta
J 0
(-5425 2400);
DISPLAY INVISIBLE (-5425 2400);
FORCEPROP 1 LAST PATH I221
J 0
(-5375 2550);
DISPLAY 0.978723 (-5375 2550);
PAINT WHITE (-5375 2550);
DISPLAY INVISIBLE (-5375 2550);
FORCEPROP 1 LAST PART_NUMBER CH11006JB18
J 0
(-5375 2250);
DISPLAY 0.510638 (-5375 2250);
DISPLAY INVISIBLE (-5375 2250);
FORCEADD UNIVERSAL_GND..1
(-5425 2125);
FORCEPROP 3 LASTPIN (-5425 2175) SIG_NAME GND\g
J 0
(-5415 2185);
DISPLAY 0.659574 (-5415 2185);
PAINT MONO (-5415 2185);
DISPLAY INVISIBLE (-5415 2185);
FORCEPROP 2 LAST CDS_LIB pure_quanta_power
J 0
(-5425 2125);
DISPLAY INVISIBLE (-5425 2125);
FORCEPROP 1 LAST HDL_POWER GND
J 1
(-5400 2050);
DISPLAY 0.872340 (-5400 2050);
PAINT GREEN (-5400 2050);
DISPLAY INVISIBLE (-5400 2050);
FORCEPROP 1 LAST PATH I222
J 0
(-5350 2125);
DISPLAY 0.872340 (-5350 2125);
PAINT AQUA (-5350 2125);
DISPLAY INVISIBLE (-5350 2125);
FORCEADD Q_CAP..1
R 2
(-5775 2400);
FORCEPROP 1 LAST LOCATION C1088
J 2
(-5600 2500);
DISPLAY 0.638298 (-5600 2500);
FORCEPROP 0 LAST $SEC 1
J 0
(-5675 2550);
DISPLAY 0.680851 (-5675 2550);
PAINT MONO (-5675 2550);
DISPLAY INVISIBLE (-5675 2550);
FORCEPROP 0 LAST CDS_SEC 1
J 0
(-5675 2550);
DISPLAY 1.021277 (-5675 2550);
DISPLAY INVISIBLE (-5675 2550);
FORCEPROP 1 LASTPIN (-5775 2500) $PN 1
J 2
(-5785 2480);
DISPLAY 0.787234 (-5785 2480);
PAINT MONO (-5785 2480);
FORCEPROP 1 LASTPIN (-5775 2300) $PN 2
J 2
(-5785 2280);
DISPLAY 0.787234 (-5785 2280);
PAINT MONO (-5785 2280);
FORCEPROP 0 LAST ROOM ADC_TI_BOM1
J 0
(-5750 2175);
DISPLAY 0.553191 (-5750 2175);
PAINT RED (-5750 2175);
FORCEPROP 1 LAST PACK_TYPE 0402
J 2
(-5600 2225);
DISPLAY 0.510638 (-5600 2225);
FORCEPROP 1 LAST TOLERANCE 10%
J 2
(-5625 2375);
DISPLAY 0.510638 (-5625 2375);
FORCEPROP 1 LAST MATERIAL X7R
J 2
(-5625 2325);
DISPLAY 0.510638 (-5625 2325);
PAINT RED (-5625 2325);
FORCEPROP 1 LAST VOLTAGE 25V
J 2
(-5625 2425);
DISPLAY 0.510638 (-5625 2425);
FORCEPROP 1 LAST VALUE 0.1UF
J 2
(-5600 2475);
DISPLAY 0.510638 (-5600 2475);
FORCEPROP 2 LAST CDS_LIB pure_quanta
J 0
(-5775 2400);
DISPLAY INVISIBLE (-5775 2400);
FORCEPROP 1 LAST PATH I223
J 2
(-5825 2550);
DISPLAY 0.978723 (-5825 2550);
PAINT WHITE (-5825 2550);
DISPLAY INVISIBLE (-5825 2550);
FORCEPROP 1 LAST PART_NUMBER CH4104K1B00
J 2
(-5475 2275);
DISPLAY 0.510638 (-5475 2275);
DISPLAY INVISIBLE (-5475 2275);
FORCEADD UNIVERSAL_GND..1
(-5775 2125);
FORCEPROP 3 LASTPIN (-5775 2175) SIG_NAME GND\g
J 0
(-5765 2185);
DISPLAY 0.659574 (-5765 2185);
PAINT MONO (-5765 2185);
DISPLAY INVISIBLE (-5765 2185);
FORCEPROP 2 LAST CDS_LIB pure_quanta_power
J 0
(-5775 2125);
DISPLAY INVISIBLE (-5775 2125);
FORCEPROP 1 LAST HDL_POWER GND
J 1
(-5750 2050);
DISPLAY 0.872340 (-5750 2050);
PAINT GREEN (-5750 2050);
DISPLAY INVISIBLE (-5750 2050);
FORCEPROP 1 LAST PATH I224
J 0
(-5700 2125);
DISPLAY 0.872340 (-5700 2125);
PAINT AQUA (-5700 2125);
DISPLAY INVISIBLE (-5700 2125);
FORCEADD Q_RES..1
(-6150 2800);
FORCEPROP 1 LAST LOCATION R1247
J 0
(-6350 2800);
DISPLAY 0.510638 (-6350 2800);
FORCEPROP 0 LAST $SEC 1
J 0
(-6275 2850);
DISPLAY 0.680851 (-6275 2850);
PAINT MONO (-6275 2850);
DISPLAY INVISIBLE (-6275 2850);
FORCEPROP 0 LAST CDS_SEC 1
J 0
(-6275 2850);
DISPLAY 1.021277 (-6275 2850);
DISPLAY INVISIBLE (-6275 2850);
FORCEPROP 1 LASTPIN (-6250 2800) $PN 1
J 0
(-6238 2812);
DISPLAY 0.787234 (-6238 2812);
PAINT MONO (-6238 2812);
FORCEPROP 1 LASTPIN (-6050 2800) $PN 2
J 0
(-6088 2812);
DISPLAY 0.787234 (-6088 2812);
PAINT MONO (-6088 2812);
FORCEPROP 1 LAST VALUE 0
J 2
(-6000 2800);
DISPLAY 0.404255 (-6000 2800);
FORCEPROP 1 LAST TOLERANCE 5%
J 0
(-5975 2800);
DISPLAY 0.404255 (-5975 2800);
FORCEPROP 1 LAST MATERIAL EMPTY
J 0
(-5925 2800);
DISPLAY 0.404255 (-5925 2800);
FORCEPROP 0 LAST ROOM ADC_MAM_BOM2
J 0
(-6300 2925);
DISPLAY 0.680851 (-6300 2925);
PAINT RED (-6300 2925);
FORCEPROP 1 LAST PACK_TYPE 0402LF
J 0
(-5900 2800);
DISPLAY 0.510638 (-5900 2800);
DISPLAY INVISIBLE (-5900 2800);
FORCEPROP 1 LAST WATTAGE 1/16W
J 2
(-6050 2725);
DISPLAY 0.319149 (-6050 2725);
DISPLAY INVISIBLE (-6050 2725);
FORCEPROP 2 LAST CDS_LIB pure_quanta
J 0
(-6150 2800);
DISPLAY INVISIBLE (-6150 2800);
FORCEPROP 1 LAST PATH I225
J 0
(-6200 2950);
DISPLAY 0.978723 (-6200 2950);
PAINT WHITE (-6200 2950);
DISPLAY INVISIBLE (-6200 2950);
FORCEPROP 1 LAST PART_NUMBER CS00002JB13
J 0
(-6225 2750);
DISPLAY 0.319149 (-6225 2750);
DISPLAY INVISIBLE (-6225 2750);
FORCEADD Q_RES..1
(-6150 2650);
FORCEPROP 1 LAST LOCATION R1254
J 0
(-6350 2650);
DISPLAY 0.510638 (-6350 2650);
FORCEPROP 0 LAST $SEC 1
J 0
(-6275 2700);
DISPLAY 0.680851 (-6275 2700);
PAINT MONO (-6275 2700);
DISPLAY INVISIBLE (-6275 2700);
FORCEPROP 0 LAST CDS_SEC 1
J 0
(-6275 2700);
DISPLAY 1.021277 (-6275 2700);
DISPLAY INVISIBLE (-6275 2700);
FORCEPROP 1 LASTPIN (-6250 2650) $PN 1
J 0
(-6238 2662);
DISPLAY 0.787234 (-6238 2662);
PAINT MONO (-6238 2662);
FORCEPROP 1 LASTPIN (-6050 2650) $PN 2
J 0
(-6088 2662);
DISPLAY 0.787234 (-6088 2662);
PAINT MONO (-6088 2662);
FORCEPROP 0 LAST ROOM ADC_TI_BOM1
J 0
(-6325 2575);
DISPLAY 0.680851 (-6325 2575);
PAINT RED (-6325 2575);
FORCEPROP 1 LAST TOLERANCE 5%
J 0
(-5975 2650);
DISPLAY 0.404255 (-5975 2650);
FORCEPROP 1 LAST VALUE 0
J 2
(-6000 2650);
DISPLAY 0.404255 (-6000 2650);
FORCEPROP 1 LAST MATERIAL CHIP
J 0
(-5925 2650);
DISPLAY 0.404255 (-5925 2650);
PAINT RED (-5925 2650);
FORCEPROP 1 LAST PACK_TYPE 0402LF
J 0
(-5900 2650);
DISPLAY 0.510638 (-5900 2650);
DISPLAY INVISIBLE (-5900 2650);
FORCEPROP 1 LAST WATTAGE 1/16W
J 2
(-6050 2575);
DISPLAY 0.319149 (-6050 2575);
DISPLAY INVISIBLE (-6050 2575);
FORCEPROP 2 LAST CDS_LIB pure_quanta
J 0
(-6150 2650);
DISPLAY INVISIBLE (-6150 2650);
FORCEPROP 1 LAST PATH I226
J 0
(-6200 2800);
DISPLAY 0.978723 (-6200 2800);
PAINT WHITE (-6200 2800);
DISPLAY INVISIBLE (-6200 2800);
FORCEPROP 1 LAST PART_NUMBER CS00002JB13
J 0
(-6225 2600);
DISPLAY 0.319149 (-6225 2600);
DISPLAY INVISIBLE (-6225 2600);
FORCEADD Q_RES..2
(-6850 3050);
FORCEPROP 1 LAST LOCATION R1233
J 0
(-6805 3175);
DISPLAY 0.510638 (-6805 3175);
FORCEPROP 2 LAST $SEC 1
J 0
(-6800 3275);
DISPLAY 0.680851 (-6800 3275);
PAINT MONO (-6800 3275);
DISPLAY INVISIBLE (-6800 3275);
FORCEPROP 2 LAST CDS_SEC 1
J 0
(-6800 3275);
DISPLAY 1.021277 (-6800 3275);
DISPLAY INVISIBLE (-6800 3275);
FORCEPROP 1 LASTPIN (-6850 3150) $PN 1
J 0
(-6845 3112);
DISPLAY 0.787234 (-6845 3112);
PAINT MONO (-6845 3112);
FORCEPROP 1 LASTPIN (-6850 2950) $PN 2
J 0
(-6845 2960);
DISPLAY 0.787234 (-6845 2960);
PAINT MONO (-6845 2960);
FORCEPROP 1 LAST VALUE 5.11K
J 0
(-6805 3125);
DISPLAY 0.510638 (-6805 3125);
FORCEPROP 1 LAST TOLERANCE 1%
J 0
(-6805 3075);
DISPLAY 0.510638 (-6805 3075);
FORCEPROP 1 LAST PACK_TYPE 0402LF
J 0
(-6810 2875);
DISPLAY 0.510638 (-6810 2875);
FORCEPROP 1 LAST MATERIAL CHIP
J 0
(-6810 2975);
DISPLAY 0.510638 (-6810 2975);
FORCEPROP 1 LAST WATTAGE 1/16W
J 0
(-6810 3025);
DISPLAY 0.510638 (-6810 3025);
FORCEPROP 2 LAST CDS_LIB pure_quanta
J 0
(-6850 3050);
DISPLAY INVISIBLE (-6850 3050);
FORCEPROP 1 LAST PATH I227
J 0
(-6800 3225);
DISPLAY 0.978723 (-6800 3225);
PAINT WHITE (-6800 3225);
DISPLAY INVISIBLE (-6800 3225);
FORCEPROP 1 LAST PART_NUMBER CS25112FB04
J 0
(-6810 2925);
DISPLAY 0.510638 (-6810 2925);
DISPLAY INVISIBLE (-6810 2925);
FORCEADD UNIVERSAL_GND..1
(-6850 2175);
FORCEPROP 3 LASTPIN (-6850 2225) SIG_NAME GND\g
J 0
(-6840 2235);
DISPLAY 0.659574 (-6840 2235);
PAINT MONO (-6840 2235);
DISPLAY INVISIBLE (-6840 2235);
FORCEPROP 2 LAST CDS_LIB pure_quanta_power
J 0
(-6850 2175);
DISPLAY INVISIBLE (-6850 2175);
FORCEPROP 1 LAST HDL_POWER GND
J 1
(-6825 2100);
DISPLAY 0.872340 (-6825 2100);
PAINT GREEN (-6825 2100);
DISPLAY INVISIBLE (-6825 2100);
FORCEPROP 1 LAST PATH I229
J 0
(-6775 2175);
DISPLAY 0.872340 (-6775 2175);
PAINT AQUA (-6775 2175);
DISPLAY INVISIBLE (-6775 2175);
FORCEADD Q_RES..2
(-6675 1525);
FORCEPROP 1 LAST LOCATION R1236
J 0
(-6630 1650);
DISPLAY 0.510638 (-6630 1650);
FORCEPROP 2 LAST $SEC 1
J 0
(-6625 1750);
DISPLAY 0.680851 (-6625 1750);
PAINT MONO (-6625 1750);
DISPLAY INVISIBLE (-6625 1750);
FORCEPROP 2 LAST CDS_SEC 1
J 0
(-6625 1750);
DISPLAY 1.021277 (-6625 1750);
DISPLAY INVISIBLE (-6625 1750);
FORCEPROP 1 LASTPIN (-6675 1625) $PN 1
J 0
(-6670 1587);
DISPLAY 0.787234 (-6670 1587);
PAINT MONO (-6670 1587);
FORCEPROP 1 LASTPIN (-6675 1425) $PN 2
J 0
(-6670 1435);
DISPLAY 0.787234 (-6670 1435);
PAINT MONO (-6670 1435);
FORCEPROP 1 LAST PACK_TYPE 0402LF
J 0
(-6635 1350);
DISPLAY 0.510638 (-6635 1350);
FORCEPROP 1 LAST WATTAGE 1/16W
J 0
(-6635 1500);
DISPLAY 0.510638 (-6635 1500);
FORCEPROP 1 LAST TOLERANCE 1%
J 0
(-6630 1550);
DISPLAY 0.510638 (-6630 1550);
FORCEPROP 1 LAST MATERIAL CHIP
J 0
(-6635 1450);
DISPLAY 0.510638 (-6635 1450);
FORCEPROP 1 LAST VALUE 5.11K
J 0
(-6630 1600);
DISPLAY 0.510638 (-6630 1600);
FORCEPROP 2 LAST CDS_LIB pure_quanta
J 0
(-6675 1525);
DISPLAY INVISIBLE (-6675 1525);
FORCEPROP 1 LAST PATH I230
J 0
(-6625 1700);
DISPLAY 0.978723 (-6625 1700);
PAINT WHITE (-6625 1700);
DISPLAY INVISIBLE (-6625 1700);
FORCEPROP 1 LAST PART_NUMBER CS25112FB04
J 0
(-6635 1400);
DISPLAY 0.510638 (-6635 1400);
DISPLAY INVISIBLE (-6635 1400);
FORCEADD Q_RES..1
(-5975 1275);
FORCEPROP 1 LAST LOCATION R1249
J 0
(-6175 1275);
DISPLAY 0.510638 (-6175 1275);
FORCEPROP 0 LAST $SEC 1
J 0
(-6100 1325);
DISPLAY 0.680851 (-6100 1325);
PAINT MONO (-6100 1325);
DISPLAY INVISIBLE (-6100 1325);
FORCEPROP 0 LAST CDS_SEC 1
J 0
(-6100 1325);
DISPLAY 1.021277 (-6100 1325);
DISPLAY INVISIBLE (-6100 1325);
FORCEPROP 1 LASTPIN (-6075 1275) $PN 1
J 0
(-6063 1287);
DISPLAY 0.787234 (-6063 1287);
PAINT MONO (-6063 1287);
FORCEPROP 1 LASTPIN (-5875 1275) $PN 2
J 0
(-5913 1287);
DISPLAY 0.787234 (-5913 1287);
PAINT MONO (-5913 1287);
FORCEPROP 0 LAST ROOM ADC_MAM_BOM2
J 0
(-6125 1375);
DISPLAY 0.680851 (-6125 1375);
PAINT RED (-6125 1375);
FORCEPROP 1 LAST TOLERANCE 5%
J 0
(-5800 1275);
DISPLAY 0.404255 (-5800 1275);
FORCEPROP 1 LAST VALUE 0
J 2
(-5825 1275);
DISPLAY 0.404255 (-5825 1275);
FORCEPROP 1 LAST MATERIAL EMPTY
J 0
(-5750 1275);
DISPLAY 0.404255 (-5750 1275);
FORCEPROP 2 LAST CDS_LIB pure_quanta
J 0
(-5975 1275);
DISPLAY INVISIBLE (-5975 1275);
FORCEPROP 1 LAST WATTAGE 1/16W
J 2
(-5875 1200);
DISPLAY 0.319149 (-5875 1200);
DISPLAY INVISIBLE (-5875 1200);
FORCEPROP 1 LAST PACK_TYPE 0402LF
J 0
(-5725 1275);
DISPLAY 0.510638 (-5725 1275);
DISPLAY INVISIBLE (-5725 1275);
FORCEPROP 1 LAST PATH I231
J 0
(-6025 1425);
DISPLAY 0.978723 (-6025 1425);
PAINT WHITE (-6025 1425);
DISPLAY INVISIBLE (-6025 1425);
FORCEPROP 1 LAST PART_NUMBER CS00002JB13
J 0
(-6050 1225);
DISPLAY 0.319149 (-6050 1225);
DISPLAY INVISIBLE (-6050 1225);
FORCEADD Q_CAP..1
(-5250 875);
FORCEPROP 1 LAST LOCATION C1081
J 0
(-5200 975);
DISPLAY 0.510638 (-5200 975);
FORCEPROP 2 LAST $SEC 1
J 0
(-5200 1075);
DISPLAY 0.680851 (-5200 1075);
PAINT MONO (-5200 1075);
DISPLAY INVISIBLE (-5200 1075);
FORCEPROP 0 LAST CDS_SEC 1
J 0
(-5200 1050);
DISPLAY 1.021277 (-5200 1050);
DISPLAY INVISIBLE (-5200 1050);
FORCEPROP 1 LASTPIN (-5250 975) $PN 1
J 0
(-5240 955);
DISPLAY 0.787234 (-5240 955);
PAINT MONO (-5240 955);
FORCEPROP 1 LASTPIN (-5250 775) $PN 2
J 0
(-5240 755);
DISPLAY 0.787234 (-5240 755);
PAINT MONO (-5240 755);
FORCEPROP 0 LAST ROOM ADC_MAM_BOM2
J 0
(-5200 625);
DISPLAY 0.680851 (-5200 625);
PAINT RED (-5200 625);
FORCEPROP 1 LAST VALUE 100PF
J 0
(-5200 925);
DISPLAY 0.510638 (-5200 925);
FORCEPROP 1 LAST PACK_TYPE 0402
J 0
(-5200 675);
DISPLAY 0.510638 (-5200 675);
FORCEPROP 1 LAST TOLERANCE 5%
J 0
(-5200 825);
DISPLAY 0.510638 (-5200 825);
FORCEPROP 1 LAST VOLTAGE 50V
J 0
(-5200 875);
DISPLAY 0.510638 (-5200 875);
FORCEPROP 1 LAST MATERIAL EMPTY
J 0
(-5200 775);
DISPLAY 0.510638 (-5200 775);
FORCEPROP 2 LAST CDS_LIB pure_quanta
J 0
(-5250 875);
DISPLAY INVISIBLE (-5250 875);
FORCEPROP 1 LAST PATH I232
J 0
(-5200 1025);
DISPLAY 0.978723 (-5200 1025);
PAINT WHITE (-5200 1025);
DISPLAY INVISIBLE (-5200 1025);
FORCEPROP 1 LAST PART_NUMBER CH11006JB18
J 0
(-5200 725);
DISPLAY 0.510638 (-5200 725);
DISPLAY INVISIBLE (-5200 725);
FORCEADD UNIVERSAL_POWER..1
(-6675 1775);
FORCEPROP 3 LASTPIN (-6675 1725) SIG_NAME PVDD18_S5_P1\g
J 0
(-6665 1735);
DISPLAY 0.659574 (-6665 1735);
PAINT MONO (-6665 1735);
DISPLAY INVISIBLE (-6665 1735);
FORCEPROP 1 LAST HDL_POWER PVDD18_S5_P1
J 1
(-6675 1825);
DISPLAY 0.872340 (-6675 1825);
PAINT GREEN (-6675 1825);
FORCEPROP 2 LAST CDS_LIB pure_quanta_power
J 0
(-6675 1775);
DISPLAY INVISIBLE (-6675 1775);
FORCEPROP 1 LAST PATH I233
J 0
(-6625 1800);
DISPLAY 0.872340 (-6625 1800);
PAINT AQUA (-6625 1800);
DISPLAY INVISIBLE (-6625 1800);
FORCEADD OFFPAGE..2
(-5100 1275);
FORCEPROP 2 LAST $XR0 259 
J 0
(-4911 1275);
DISPLAY 0.638298 (-4911 1275);
PAINT MONO (-4911 1275);
FORCEPROP 2 LAST CDS_LIB standard
J 0
(-5100 1275);
DISPLAY INVISIBLE (-5100 1275);
FORCEPROP 1 LAST OFFPAGE TRUE
J 0
(-4775 1150);
DISPLAY 0.872340 (-4775 1150);
DISPLAY INVISIBLE (-4775 1150);
FORCEPROP 1 LAST COMMENT_BODY TRUE
J 0
(-5145 1180);
DISPLAY 0.872340 (-5145 1180);
PAINT GREEN (-5145 1180);
DISPLAY INVISIBLE (-5145 1180);
FORCEPROP 2 LAST PATH I234
J 0
(-4900 1325);
DISPLAY 0.680851 (-4900 1325);
DISPLAY INVISIBLE (-4900 1325);
FORCEADD OFFPAGE..2
(-5100 1125);
FORCEPROP 2 LAST $XR0 259 
J 0
(-4911 1125);
DISPLAY 0.638298 (-4911 1125);
PAINT MONO (-4911 1125);
FORCEPROP 2 LAST CDS_LIB standard
J 0
(-5100 1125);
DISPLAY INVISIBLE (-5100 1125);
FORCEPROP 1 LAST OFFPAGE TRUE
J 0
(-4775 1000);
DISPLAY 0.872340 (-4775 1000);
DISPLAY INVISIBLE (-4775 1000);
FORCEPROP 1 LAST COMMENT_BODY TRUE
J 0
(-5145 1030);
DISPLAY 0.872340 (-5145 1030);
PAINT GREEN (-5145 1030);
DISPLAY INVISIBLE (-5145 1030);
FORCEPROP 2 LAST PATH I235
J 0
(-4900 1175);
DISPLAY 0.680851 (-4900 1175);
DISPLAY INVISIBLE (-4900 1175);
FORCEADD UNIVERSAL_GND..1
(-5250 600);
FORCEPROP 3 LASTPIN (-5250 650) SIG_NAME GND\g
J 0
(-5240 660);
DISPLAY 0.659574 (-5240 660);
PAINT MONO (-5240 660);
DISPLAY INVISIBLE (-5240 660);
FORCEPROP 2 LAST CDS_LIB pure_quanta_power
J 0
(-5250 600);
DISPLAY INVISIBLE (-5250 600);
FORCEPROP 1 LAST HDL_POWER GND
J 1
(-5225 525);
DISPLAY 0.872340 (-5225 525);
PAINT GREEN (-5225 525);
DISPLAY INVISIBLE (-5225 525);
FORCEPROP 1 LAST PATH I236
J 0
(-5175 600);
DISPLAY 0.872340 (-5175 600);
PAINT AQUA (-5175 600);
DISPLAY INVISIBLE (-5175 600);
FORCEADD Q_CAP..1
R 2
(-5600 875);
FORCEPROP 1 LAST LOCATION C1090
J 2
(-5425 975);
DISPLAY 0.638298 (-5425 975);
FORCEPROP 0 LAST $SEC 1
J 0
(-5500 1025);
DISPLAY 0.680851 (-5500 1025);
PAINT MONO (-5500 1025);
DISPLAY INVISIBLE (-5500 1025);
FORCEPROP 0 LAST CDS_SEC 1
J 0
(-5500 1025);
DISPLAY 1.021277 (-5500 1025);
DISPLAY INVISIBLE (-5500 1025);
FORCEPROP 1 LASTPIN (-5600 975) $PN 1
J 2
(-5610 955);
DISPLAY 0.787234 (-5610 955);
PAINT MONO (-5610 955);
FORCEPROP 1 LASTPIN (-5600 775) $PN 2
J 2
(-5610 755);
DISPLAY 0.787234 (-5610 755);
PAINT MONO (-5610 755);
FORCEPROP 1 LAST VOLTAGE 25V
J 2
(-5450 900);
DISPLAY 0.510638 (-5450 900);
FORCEPROP 1 LAST TOLERANCE 10%
J 2
(-5450 850);
DISPLAY 0.510638 (-5450 850);
FORCEPROP 1 LAST MATERIAL X7R
J 2
(-5450 800);
DISPLAY 0.510638 (-5450 800);
PAINT RED (-5450 800);
FORCEPROP 1 LAST VALUE 0.1UF
J 2
(-5425 950);
DISPLAY 0.510638 (-5425 950);
FORCEPROP 1 LAST PACK_TYPE 0402
J 2
(-5425 700);
DISPLAY 0.510638 (-5425 700);
FORCEPROP 0 LAST ROOM ADC_TI_BOM1
J 0
(-5575 650);
DISPLAY 0.553191 (-5575 650);
PAINT RED (-5575 650);
FORCEPROP 2 LAST CDS_LIB pure_quanta
J 0
(-5600 875);
DISPLAY INVISIBLE (-5600 875);
FORCEPROP 1 LAST PATH I237
J 2
(-5650 1025);
DISPLAY 0.978723 (-5650 1025);
PAINT WHITE (-5650 1025);
DISPLAY INVISIBLE (-5650 1025);
FORCEPROP 1 LAST PART_NUMBER CH4104K1B00
J 2
(-5300 750);
DISPLAY 0.510638 (-5300 750);
DISPLAY INVISIBLE (-5300 750);
FORCEADD UNIVERSAL_GND..1
(-5600 600);
FORCEPROP 3 LASTPIN (-5600 650) SIG_NAME GND\g
J 0
(-5590 660);
DISPLAY 0.659574 (-5590 660);
PAINT MONO (-5590 660);
DISPLAY INVISIBLE (-5590 660);
FORCEPROP 2 LAST CDS_LIB pure_quanta_power
J 0
(-5600 600);
DISPLAY INVISIBLE (-5600 600);
FORCEPROP 1 LAST HDL_POWER GND
J 1
(-5575 525);
DISPLAY 0.872340 (-5575 525);
PAINT GREEN (-5575 525);
DISPLAY INVISIBLE (-5575 525);
FORCEPROP 1 LAST PATH I238
J 0
(-5525 600);
DISPLAY 0.872340 (-5525 600);
PAINT AQUA (-5525 600);
DISPLAY INVISIBLE (-5525 600);
FORCEADD Q_RES..1
(-5975 1125);
FORCEPROP 1 LAST LOCATION R1256
J 0
(-6175 1125);
DISPLAY 0.510638 (-6175 1125);
FORCEPROP 0 LAST $SEC 1
J 0
(-6100 1175);
DISPLAY 0.680851 (-6100 1175);
PAINT MONO (-6100 1175);
DISPLAY INVISIBLE (-6100 1175);
FORCEPROP 0 LAST CDS_SEC 1
J 0
(-6100 1175);
DISPLAY 1.021277 (-6100 1175);
DISPLAY INVISIBLE (-6100 1175);
FORCEPROP 1 LASTPIN (-6075 1125) $PN 1
J 0
(-6063 1137);
DISPLAY 0.787234 (-6063 1137);
PAINT MONO (-6063 1137);
FORCEPROP 1 LASTPIN (-5875 1125) $PN 2
J 0
(-5913 1137);
DISPLAY 0.787234 (-5913 1137);
PAINT MONO (-5913 1137);
FORCEPROP 1 LAST MATERIAL CHIP
J 0
(-5750 1125);
DISPLAY 0.404255 (-5750 1125);
PAINT RED (-5750 1125);
FORCEPROP 1 LAST TOLERANCE 5%
J 0
(-5800 1125);
DISPLAY 0.404255 (-5800 1125);
FORCEPROP 1 LAST VALUE 0
J 2
(-5825 1125);
DISPLAY 0.404255 (-5825 1125);
FORCEPROP 0 LAST ROOM ADC_TI_BOM1
J 0
(-6125 1050);
DISPLAY 0.680851 (-6125 1050);
PAINT RED (-6125 1050);
FORCEPROP 2 LAST CDS_LIB pure_quanta
J 0
(-5975 1125);
DISPLAY INVISIBLE (-5975 1125);
FORCEPROP 1 LAST WATTAGE 1/16W
J 2
(-5875 1050);
DISPLAY 0.319149 (-5875 1050);
DISPLAY INVISIBLE (-5875 1050);
FORCEPROP 1 LAST PACK_TYPE 0402LF
J 0
(-5725 1125);
DISPLAY 0.510638 (-5725 1125);
DISPLAY INVISIBLE (-5725 1125);
FORCEPROP 1 LAST PATH I239
J 0
(-6025 1275);
DISPLAY 0.978723 (-6025 1275);
PAINT WHITE (-6025 1275);
DISPLAY INVISIBLE (-6025 1275);
FORCEPROP 1 LAST PART_NUMBER CS00002JB13
J 0
(-6050 1075);
DISPLAY 0.319149 (-6050 1075);
DISPLAY INVISIBLE (-6050 1075);
FORCEADD UNIVERSAL_GND..1
(-6675 650);
FORCEPROP 3 LASTPIN (-6675 700) SIG_NAME GND\g
J 0
(-6665 710);
DISPLAY 0.659574 (-6665 710);
PAINT MONO (-6665 710);
DISPLAY INVISIBLE (-6665 710);
FORCEPROP 2 LAST CDS_LIB pure_quanta_power
J 0
(-6675 650);
DISPLAY INVISIBLE (-6675 650);
FORCEPROP 1 LAST HDL_POWER GND
J 1
(-6650 575);
DISPLAY 0.872340 (-6650 575);
PAINT GREEN (-6650 575);
DISPLAY INVISIBLE (-6650 575);
FORCEPROP 1 LAST PATH I241
J 0
(-6600 650);
DISPLAY 0.872340 (-6600 650);
PAINT AQUA (-6600 650);
DISPLAY INVISIBLE (-6600 650);
FORCEADD Q_RES..2
(-8975 4225);
FORCEPROP 1 LAST LOCATION R1229
J 0
(-8930 4350);
DISPLAY 0.638298 (-8930 4350);
FORCEPROP 0 LAST $SEC 1
J 0
(-8925 4400);
DISPLAY 0.680851 (-8925 4400);
PAINT MONO (-8925 4400);
DISPLAY INVISIBLE (-8925 4400);
FORCEPROP 0 LAST CDS_SEC 1
J 0
(-8925 4400);
DISPLAY 0.680851 (-8925 4400);
DISPLAY INVISIBLE (-8925 4400);
FORCEPROP 1 LASTPIN (-8975 4325) $PN 1
J 0
(-8970 4287);
DISPLAY 0.787234 (-8970 4287);
PAINT MONO (-8970 4287);
FORCEPROP 1 LASTPIN (-8975 4125) $PN 2
J 0
(-8970 4135);
DISPLAY 0.787234 (-8970 4135);
PAINT MONO (-8970 4135);
FORCEPROP 1 LAST TOLERANCE 1%
J 0
(-8930 4250);
DISPLAY 0.510638 (-8930 4250);
FORCEPROP 1 LAST VALUE 18K
J 0
(-8930 4300);
DISPLAY 0.510638 (-8930 4300);
FORCEPROP 1 LAST MATERIAL CHIP
J 0
(-8935 4150);
DISPLAY 0.510638 (-8935 4150);
FORCEPROP 1 LAST WATTAGE 1/16W
J 0
(-8935 4200);
DISPLAY 0.510638 (-8935 4200);
FORCEPROP 1 LAST PACK_TYPE 0402LF
J 0
(-8935 4050);
DISPLAY 0.510638 (-8935 4050);
FORCEPROP 2 LAST CDS_LIB pure_quanta
J 0
(-8975 4225);
DISPLAY INVISIBLE (-8975 4225);
FORCEPROP 1 LAST PATH I242
J 0
(-8925 4400);
DISPLAY 0.978723 (-8925 4400);
PAINT WHITE (-8925 4400);
DISPLAY INVISIBLE (-8925 4400);
FORCEPROP 1 LAST PART_NUMBER CS31802FB04
J 0
(-8935 4100);
DISPLAY 0.510638 (-8935 4100);
DISPLAY INVISIBLE (-8935 4100);
FORCEADD Q_RES..2
(-8950 2700);
FORCEPROP 1 LAST LOCATION R1221
J 0
(-8905 2825);
DISPLAY 0.638298 (-8905 2825);
FORCEPROP 0 LAST $SEC 1
J 0
(-8900 2875);
DISPLAY 0.680851 (-8900 2875);
PAINT MONO (-8900 2875);
DISPLAY INVISIBLE (-8900 2875);
FORCEPROP 0 LAST CDS_SEC 1
J 0
(-8900 2875);
DISPLAY 0.680851 (-8900 2875);
DISPLAY INVISIBLE (-8900 2875);
FORCEPROP 1 LASTPIN (-8950 2800) $PN 1
J 0
(-8945 2762);
DISPLAY 0.787234 (-8945 2762);
PAINT MONO (-8945 2762);
FORCEPROP 1 LASTPIN (-8950 2600) $PN 2
J 0
(-8945 2610);
DISPLAY 0.787234 (-8945 2610);
PAINT MONO (-8945 2610);
FORCEPROP 1 LAST TOLERANCE 1%
J 0
(-8905 2725);
DISPLAY 0.510638 (-8905 2725);
FORCEPROP 1 LAST MATERIAL CHIP
J 0
(-8910 2625);
DISPLAY 0.510638 (-8910 2625);
FORCEPROP 1 LAST VALUE 18K
J 0
(-8905 2775);
DISPLAY 0.510638 (-8905 2775);
FORCEPROP 1 LAST WATTAGE 1/16W
J 0
(-8910 2675);
DISPLAY 0.510638 (-8910 2675);
FORCEPROP 1 LAST PACK_TYPE 0402LF
J 0
(-8910 2525);
DISPLAY 0.510638 (-8910 2525);
FORCEPROP 2 LAST CDS_LIB pure_quanta
J 0
(-8950 2700);
DISPLAY INVISIBLE (-8950 2700);
FORCEPROP 1 LAST PATH I243
J 0
(-8900 2875);
DISPLAY 0.978723 (-8900 2875);
PAINT WHITE (-8900 2875);
DISPLAY INVISIBLE (-8900 2875);
FORCEPROP 1 LAST PART_NUMBER CS31802FB04
J 0
(-8910 2575);
DISPLAY 0.510638 (-8910 2575);
DISPLAY INVISIBLE (-8910 2575);
FORCEADD Q_RES..2
(-9025 1100);
FORCEPROP 1 LAST LOCATION R1220
J 0
(-8980 1225);
DISPLAY 0.638298 (-8980 1225);
FORCEPROP 0 LAST $SEC 1
J 0
(-8975 1275);
DISPLAY 0.680851 (-8975 1275);
PAINT MONO (-8975 1275);
DISPLAY INVISIBLE (-8975 1275);
FORCEPROP 0 LAST CDS_SEC 1
J 0
(-8975 1275);
DISPLAY 0.680851 (-8975 1275);
DISPLAY INVISIBLE (-8975 1275);
FORCEPROP 1 LASTPIN (-9025 1200) $PN 1
J 0
(-9020 1162);
DISPLAY 0.787234 (-9020 1162);
PAINT MONO (-9020 1162);
FORCEPROP 1 LASTPIN (-9025 1000) $PN 2
J 0
(-9020 1010);
DISPLAY 0.787234 (-9020 1010);
PAINT MONO (-9020 1010);
FORCEPROP 1 LAST PACK_TYPE 0402LF
J 0
(-8985 925);
DISPLAY 0.510638 (-8985 925);
FORCEPROP 1 LAST MATERIAL CHIP
J 0
(-8985 1025);
DISPLAY 0.510638 (-8985 1025);
FORCEPROP 1 LAST VALUE 18K
J 0
(-8980 1175);
DISPLAY 0.510638 (-8980 1175);
FORCEPROP 1 LAST WATTAGE 1/16W
J 0
(-8985 1075);
DISPLAY 0.510638 (-8985 1075);
FORCEPROP 1 LAST TOLERANCE 1%
J 0
(-8980 1125);
DISPLAY 0.510638 (-8980 1125);
FORCEPROP 2 LAST CDS_LIB pure_quanta
J 0
(-9025 1100);
DISPLAY INVISIBLE (-9025 1100);
FORCEPROP 1 LAST PATH I244
J 0
(-8975 1275);
DISPLAY 0.978723 (-8975 1275);
PAINT WHITE (-8975 1275);
DISPLAY INVISIBLE (-8975 1275);
FORCEPROP 1 LAST PART_NUMBER CS31802FB04
J 0
(-8985 975);
DISPLAY 0.510638 (-8985 975);
DISPLAY INVISIBLE (-8985 975);
FORCEADD Q_RES..2
(-6800 5500);
FORCEPROP 1 LAST LOCATION R1223
J 0
(-6755 5625);
DISPLAY 0.638298 (-6755 5625);
FORCEPROP 0 LAST $SEC 1
J 0
(-6750 5675);
DISPLAY 0.680851 (-6750 5675);
PAINT MONO (-6750 5675);
DISPLAY INVISIBLE (-6750 5675);
FORCEPROP 0 LAST CDS_SEC 1
J 0
(-6750 5675);
DISPLAY 0.680851 (-6750 5675);
DISPLAY INVISIBLE (-6750 5675);
FORCEPROP 1 LASTPIN (-6800 5600) $PN 1
J 0
(-6795 5562);
DISPLAY 0.787234 (-6795 5562);
PAINT MONO (-6795 5562);
FORCEPROP 1 LASTPIN (-6800 5400) $PN 2
J 0
(-6795 5410);
DISPLAY 0.787234 (-6795 5410);
PAINT MONO (-6795 5410);
FORCEPROP 1 LAST TOLERANCE 1%
J 0
(-6755 5525);
DISPLAY 0.510638 (-6755 5525);
FORCEPROP 1 LAST PACK_TYPE 0402LF
J 0
(-6760 5325);
DISPLAY 0.510638 (-6760 5325);
FORCEPROP 1 LAST VALUE 18K
J 0
(-6755 5575);
DISPLAY 0.510638 (-6755 5575);
FORCEPROP 1 LAST MATERIAL CHIP
J 0
(-6760 5425);
DISPLAY 0.510638 (-6760 5425);
FORCEPROP 1 LAST WATTAGE 1/16W
J 0
(-6760 5475);
DISPLAY 0.510638 (-6760 5475);
FORCEPROP 2 LAST CDS_LIB pure_quanta
J 0
(-6800 5500);
DISPLAY INVISIBLE (-6800 5500);
FORCEPROP 1 LAST PATH I245
J 0
(-6750 5675);
DISPLAY 0.978723 (-6750 5675);
PAINT WHITE (-6750 5675);
DISPLAY INVISIBLE (-6750 5675);
FORCEPROP 1 LAST PART_NUMBER CS31802FB04
J 0
(-6760 5375);
DISPLAY 0.510638 (-6760 5375);
DISPLAY INVISIBLE (-6760 5375);
FORCEADD Q_RES..2
(-6850 2525);
FORCEPROP 1 LAST LOCATION R1222
J 0
(-6805 2650);
DISPLAY 0.638298 (-6805 2650);
FORCEPROP 0 LAST $SEC 1
J 0
(-6800 2700);
DISPLAY 0.680851 (-6800 2700);
PAINT MONO (-6800 2700);
DISPLAY INVISIBLE (-6800 2700);
FORCEPROP 0 LAST CDS_SEC 1
J 0
(-6800 2700);
DISPLAY 0.680851 (-6800 2700);
DISPLAY INVISIBLE (-6800 2700);
FORCEPROP 1 LASTPIN (-6850 2625) $PN 1
J 0
(-6845 2587);
DISPLAY 0.787234 (-6845 2587);
PAINT MONO (-6845 2587);
FORCEPROP 1 LASTPIN (-6850 2425) $PN 2
J 0
(-6845 2435);
DISPLAY 0.787234 (-6845 2435);
PAINT MONO (-6845 2435);
FORCEPROP 1 LAST PACK_TYPE 0402LF
J 0
(-6810 2350);
DISPLAY 0.510638 (-6810 2350);
FORCEPROP 1 LAST VALUE 18K
J 0
(-6805 2600);
DISPLAY 0.510638 (-6805 2600);
FORCEPROP 1 LAST MATERIAL CHIP
J 0
(-6810 2450);
DISPLAY 0.510638 (-6810 2450);
FORCEPROP 1 LAST WATTAGE 1/16W
J 0
(-6810 2500);
DISPLAY 0.510638 (-6810 2500);
FORCEPROP 1 LAST TOLERANCE 1%
J 0
(-6805 2550);
DISPLAY 0.510638 (-6805 2550);
FORCEPROP 2 LAST CDS_LIB pure_quanta
J 0
(-6850 2525);
DISPLAY INVISIBLE (-6850 2525);
FORCEPROP 1 LAST PATH I246
J 0
(-6800 2700);
DISPLAY 0.978723 (-6800 2700);
PAINT WHITE (-6800 2700);
DISPLAY INVISIBLE (-6800 2700);
FORCEPROP 1 LAST PART_NUMBER CS31802FB04
J 0
(-6810 2400);
DISPLAY 0.510638 (-6810 2400);
DISPLAY INVISIBLE (-6810 2400);
FORCEADD Q_RES..2
(-6675 1000);
FORCEPROP 1 LAST LOCATION R1225
J 0
(-6630 1125);
DISPLAY 0.638298 (-6630 1125);
FORCEPROP 0 LAST $SEC 1
J 0
(-6625 1175);
DISPLAY 0.680851 (-6625 1175);
PAINT MONO (-6625 1175);
DISPLAY INVISIBLE (-6625 1175);
FORCEPROP 0 LAST CDS_SEC 1
J 0
(-6625 1175);
DISPLAY 0.680851 (-6625 1175);
DISPLAY INVISIBLE (-6625 1175);
FORCEPROP 1 LASTPIN (-6675 1100) $PN 1
J 0
(-6670 1062);
DISPLAY 0.787234 (-6670 1062);
PAINT MONO (-6670 1062);
FORCEPROP 1 LASTPIN (-6675 900) $PN 2
J 0
(-6670 910);
DISPLAY 0.787234 (-6670 910);
PAINT MONO (-6670 910);
FORCEPROP 1 LAST MATERIAL CHIP
J 0
(-6635 925);
DISPLAY 0.510638 (-6635 925);
FORCEPROP 1 LAST VALUE 18K
J 0
(-6630 1075);
DISPLAY 0.510638 (-6630 1075);
FORCEPROP 1 LAST TOLERANCE 1%
J 0
(-6630 1025);
DISPLAY 0.510638 (-6630 1025);
FORCEPROP 1 LAST PACK_TYPE 0402LF
J 0
(-6635 825);
DISPLAY 0.510638 (-6635 825);
FORCEPROP 1 LAST WATTAGE 1/16W
J 0
(-6635 975);
DISPLAY 0.510638 (-6635 975);
FORCEPROP 2 LAST CDS_LIB pure_quanta
J 0
(-6675 1000);
DISPLAY INVISIBLE (-6675 1000);
FORCEPROP 1 LAST PATH I247
J 0
(-6625 1175);
DISPLAY 0.978723 (-6625 1175);
PAINT WHITE (-6625 1175);
DISPLAY INVISIBLE (-6625 1175);
FORCEPROP 1 LAST PART_NUMBER CS31802FB04
J 0
(-6635 875);
DISPLAY 0.510638 (-6635 875);
DISPLAY INVISIBLE (-6635 875);
FORCEADD UNIVERSAL_GND..1
(-8050 5075);
FORCEPROP 3 LASTPIN (-8050 5125) SIG_NAME GND\g
J 0
(-8040 5135);
DISPLAY 0.659574 (-8040 5135);
PAINT MONO (-8040 5135);
DISPLAY INVISIBLE (-8040 5135);
FORCEPROP 2 LAST CDS_LIB pure_quanta_power
J 0
(-8050 5075);
DISPLAY INVISIBLE (-8050 5075);
FORCEPROP 1 LAST HDL_POWER GND
J 1
(-8025 5000);
DISPLAY 0.872340 (-8025 5000);
PAINT GREEN (-8025 5000);
DISPLAY INVISIBLE (-8025 5000);
FORCEPROP 1 LAST PATH I42
J 0
(-7975 5075);
DISPLAY 0.872340 (-7975 5075);
PAINT AQUA (-7975 5075);
DISPLAY INVISIBLE (-7975 5075);
FORCEADD Q_CAP..1
R 2
(-8050 5350);
FORCEPROP 1 LAST LOCATION C1093
J 2
(-7900 5450);
DISPLAY 0.638298 (-7900 5450);
FORCEPROP 0 LAST $SEC 1
J 0
(-7950 5500);
DISPLAY 0.680851 (-7950 5500);
PAINT MONO (-7950 5500);
DISPLAY INVISIBLE (-7950 5500);
FORCEPROP 0 LAST CDS_SEC 1
J 0
(-7950 5500);
DISPLAY 1.021277 (-7950 5500);
DISPLAY INVISIBLE (-7950 5500);
FORCEPROP 1 LASTPIN (-8050 5450) $PN 1
J 2
(-8060 5430);
DISPLAY 0.787234 (-8060 5430);
PAINT MONO (-8060 5430);
FORCEPROP 1 LASTPIN (-8050 5250) $PN 2
J 2
(-8060 5230);
DISPLAY 0.787234 (-8060 5230);
PAINT MONO (-8060 5230);
FORCEPROP 0 LAST ROOM ADC_TI_BOM1
J 0
(-8025 5500);
DISPLAY 0.553191 (-8025 5500);
PAINT RED (-8025 5500);
FORCEPROP 1 LAST VALUE 0.1UF
J 2
(-7875 5425);
DISPLAY 0.510638 (-7875 5425);
FORCEPROP 1 LAST VOLTAGE 25V
J 2
(-7900 5375);
DISPLAY 0.510638 (-7900 5375);
FORCEPROP 1 LAST TOLERANCE 10%
J 2
(-7900 5325);
DISPLAY 0.510638 (-7900 5325);
FORCEPROP 1 LAST MATERIAL X7R
J 2
(-7900 5275);
DISPLAY 0.510638 (-7900 5275);
PAINT RED (-7900 5275);
FORCEPROP 1 LAST PACK_TYPE 0402
J 2
(-7875 5175);
DISPLAY 0.510638 (-7875 5175);
FORCEPROP 2 LAST CDS_LIB pure_quanta
J 0
(-8050 5350);
DISPLAY INVISIBLE (-8050 5350);
FORCEPROP 1 LAST PATH I43
J 2
(-8100 5500);
DISPLAY 0.978723 (-8100 5500);
PAINT WHITE (-8100 5500);
DISPLAY INVISIBLE (-8100 5500);
FORCEPROP 1 LAST PART_NUMBER CH4104K1B00
J 2
(-7750 5225);
DISPLAY 0.510638 (-7750 5225);
DISPLAY INVISIBLE (-7750 5225);
FORCEADD UNIVERSAL_GND..1
(-7700 5075);
FORCEPROP 3 LASTPIN (-7700 5125) SIG_NAME GND\g
J 0
(-7690 5135);
DISPLAY 0.659574 (-7690 5135);
PAINT MONO (-7690 5135);
DISPLAY INVISIBLE (-7690 5135);
FORCEPROP 2 LAST CDS_LIB pure_quanta_power
J 0
(-7700 5075);
DISPLAY INVISIBLE (-7700 5075);
FORCEPROP 1 LAST HDL_POWER GND
J 1
(-7675 5000);
DISPLAY 0.872340 (-7675 5000);
PAINT GREEN (-7675 5000);
DISPLAY INVISIBLE (-7675 5000);
FORCEPROP 1 LAST PATH I44
J 0
(-7625 5075);
DISPLAY 0.872340 (-7625 5075);
PAINT AQUA (-7625 5075);
DISPLAY INVISIBLE (-7625 5075);
FORCEADD Q_CAP..1
(-7700 5350);
FORCEPROP 1 LAST LOCATION C1085
J 0
(-7650 5450);
DISPLAY 0.510638 (-7650 5450);
FORCEPROP 2 LAST $SEC 1
J 0
(-7650 5550);
DISPLAY 0.680851 (-7650 5550);
PAINT MONO (-7650 5550);
DISPLAY INVISIBLE (-7650 5550);
FORCEPROP 0 LAST CDS_SEC 1
J 0
(-7650 5525);
DISPLAY 1.021277 (-7650 5525);
DISPLAY INVISIBLE (-7650 5525);
FORCEPROP 1 LASTPIN (-7700 5450) $PN 1
J 0
(-7690 5430);
DISPLAY 0.787234 (-7690 5430);
PAINT MONO (-7690 5430);
FORCEPROP 1 LASTPIN (-7700 5250) $PN 2
J 0
(-7690 5230);
DISPLAY 0.787234 (-7690 5230);
PAINT MONO (-7690 5230);
FORCEPROP 1 LAST TOLERANCE 5%
J 0
(-7650 5300);
DISPLAY 0.510638 (-7650 5300);
FORCEPROP 1 LAST MATERIAL EMPTY
J 0
(-7650 5250);
DISPLAY 0.510638 (-7650 5250);
FORCEPROP 1 LAST VOLTAGE 50V
J 0
(-7650 5350);
DISPLAY 0.510638 (-7650 5350);
FORCEPROP 1 LAST VALUE 100PF
J 0
(-7650 5400);
DISPLAY 0.510638 (-7650 5400);
FORCEPROP 1 LAST PACK_TYPE 0402
J 0
(-7650 5150);
DISPLAY 0.510638 (-7650 5150);
FORCEPROP 0 LAST ROOM ADC_MAM_BOM2
J 0
(-7650 5500);
DISPLAY 0.553191 (-7650 5500);
PAINT RED (-7650 5500);
FORCEPROP 2 LAST CDS_LIB pure_quanta
J 0
(-7700 5350);
DISPLAY INVISIBLE (-7700 5350);
FORCEPROP 1 LAST PATH I45
J 0
(-7650 5500);
DISPLAY 0.978723 (-7650 5500);
PAINT WHITE (-7650 5500);
DISPLAY INVISIBLE (-7650 5500);
FORCEPROP 1 LAST PART_NUMBER CH11006JB18
J 0
(-7650 5200);
DISPLAY 0.510638 (-7650 5200);
DISPLAY INVISIBLE (-7650 5200);
FORCEADD UNIVERSAL_GND..1
(-7975 3750);
FORCEPROP 3 LASTPIN (-7975 3800) SIG_NAME GND\g
J 0
(-7965 3810);
DISPLAY 0.659574 (-7965 3810);
PAINT MONO (-7965 3810);
DISPLAY INVISIBLE (-7965 3810);
FORCEPROP 2 LAST CDS_LIB pure_quanta_power
J 0
(-7975 3750);
DISPLAY INVISIBLE (-7975 3750);
FORCEPROP 1 LAST HDL_POWER GND
J 1
(-7950 3675);
DISPLAY 0.872340 (-7950 3675);
PAINT GREEN (-7950 3675);
DISPLAY INVISIBLE (-7950 3675);
FORCEPROP 1 LAST PATH I46
J 0
(-7900 3750);
DISPLAY 0.872340 (-7900 3750);
PAINT AQUA (-7900 3750);
DISPLAY INVISIBLE (-7900 3750);
FORCEADD OFFPAGE..2
(-7575 5625);
FORCEPROP 2 LAST $XR0 259 
J 0
(-7386 5625);
DISPLAY 0.638298 (-7386 5625);
PAINT MONO (-7386 5625);
FORCEPROP 2 LAST CDS_LIB standard
J 0
(-7575 5625);
DISPLAY INVISIBLE (-7575 5625);
FORCEPROP 1 LAST OFFPAGE TRUE
J 0
(-7250 5500);
DISPLAY 0.872340 (-7250 5500);
DISPLAY INVISIBLE (-7250 5500);
FORCEPROP 1 LAST COMMENT_BODY TRUE
J 0
(-7620 5530);
DISPLAY 0.872340 (-7620 5530);
PAINT GREEN (-7620 5530);
DISPLAY INVISIBLE (-7620 5530);
FORCEPROP 2 LAST PATH I47
J 0
(-7375 5675);
DISPLAY 0.680851 (-7375 5675);
DISPLAY INVISIBLE (-7375 5675);
FORCEADD OFFPAGE..2
(-7575 5775);
FORCEPROP 2 LAST $XR0 259 
J 0
(-7386 5775);
DISPLAY 0.638298 (-7386 5775);
PAINT MONO (-7386 5775);
FORCEPROP 2 LAST CDS_LIB standard
J 0
(-7575 5775);
DISPLAY INVISIBLE (-7575 5775);
FORCEPROP 1 LAST OFFPAGE TRUE
J 0
(-7250 5650);
DISPLAY 0.872340 (-7250 5650);
DISPLAY INVISIBLE (-7250 5650);
FORCEPROP 1 LAST COMMENT_BODY TRUE
J 0
(-7620 5680);
DISPLAY 0.872340 (-7620 5680);
PAINT GREEN (-7620 5680);
DISPLAY INVISIBLE (-7620 5680);
FORCEPROP 2 LAST PATH I48
J 0
(-7375 5825);
DISPLAY 0.680851 (-7375 5825);
DISPLAY INVISIBLE (-7375 5825);
FORCEADD UNIVERSAL_GND..1
(-7625 3750);
FORCEPROP 3 LASTPIN (-7625 3800) SIG_NAME GND\g
J 0
(-7615 3810);
DISPLAY 0.659574 (-7615 3810);
PAINT MONO (-7615 3810);
DISPLAY INVISIBLE (-7615 3810);
FORCEPROP 2 LAST CDS_LIB pure_quanta_power
J 0
(-7625 3750);
DISPLAY INVISIBLE (-7625 3750);
FORCEPROP 1 LAST HDL_POWER GND
J 1
(-7600 3675);
DISPLAY 0.872340 (-7600 3675);
PAINT GREEN (-7600 3675);
DISPLAY INVISIBLE (-7600 3675);
FORCEPROP 1 LAST PATH I49
J 0
(-7550 3750);
DISPLAY 0.872340 (-7550 3750);
PAINT AQUA (-7550 3750);
DISPLAY INVISIBLE (-7550 3750);
FORCEADD UNIVERSAL_GND..1
(-4250 350);
FORCEPROP 3 LASTPIN (-4250 400) SIG_NAME GND\g
J 0
(-4240 410);
DISPLAY 0.659574 (-4240 410);
PAINT MONO (-4240 410);
DISPLAY INVISIBLE (-4240 410);
FORCEPROP 2 LAST CDS_LIB pure_quanta_power
J 0
(-4250 350);
PAINT MONO (-4250 350);
DISPLAY INVISIBLE (-4250 350);
FORCEPROP 1 LAST HDL_POWER GND
J 1
(-4225 275);
DISPLAY 0.872340 (-4225 275);
PAINT GREEN (-4225 275);
DISPLAY INVISIBLE (-4225 275);
FORCEPROP 1 LAST PATH I55
J 0
(-4175 350);
DISPLAY 0.872340 (-4175 350);
PAINT AQUA (-4175 350);
DISPLAY INVISIBLE (-4175 350);
FORCEADD UNIVERSAL_GND..1
(-4500 350);
FORCEPROP 3 LASTPIN (-4500 400) SIG_NAME GND\g
J 0
(-4490 410);
DISPLAY 0.659574 (-4490 410);
PAINT MONO (-4490 410);
DISPLAY INVISIBLE (-4490 410);
FORCEPROP 2 LAST CDS_LIB pure_quanta_power
J 0
(-4500 350);
PAINT MONO (-4500 350);
DISPLAY INVISIBLE (-4500 350);
FORCEPROP 1 LAST HDL_POWER GND
J 1
(-4475 275);
DISPLAY 0.872340 (-4475 275);
PAINT GREEN (-4475 275);
DISPLAY INVISIBLE (-4475 275);
FORCEPROP 1 LAST PATH I56
J 0
(-4425 350);
DISPLAY 0.872340 (-4425 350);
PAINT AQUA (-4425 350);
DISPLAY INVISIBLE (-4425 350);
FORCEADD Q_RES..2
(-4500 575);
FORCEPROP 1 LAST LOCATION R1240
J 0
(-4455 700);
DISPLAY 0.638298 (-4455 700);
FORCEPROP 0 LAST $SEC 1
J 0
(-4450 750);
DISPLAY 0.680851 (-4450 750);
PAINT MONO (-4450 750);
DISPLAY INVISIBLE (-4450 750);
FORCEPROP 0 LAST CDS_SEC 1
J 0
(-4450 750);
DISPLAY 1.021277 (-4450 750);
DISPLAY INVISIBLE (-4450 750);
FORCEPROP 1 LASTPIN (-4500 675) $PN 1
J 0
(-4495 637);
DISPLAY 0.787234 (-4495 637);
PAINT MONO (-4495 637);
FORCEPROP 1 LASTPIN (-4500 475) $PN 2
J 0
(-4495 485);
DISPLAY 0.787234 (-4495 485);
PAINT MONO (-4495 485);
FORCEPROP 0 LAST ROOM ADC_TI_BOM1
J 0
(-4575 750);
DISPLAY 0.553191 (-4575 750);
PAINT RED (-4575 750);
FORCEPROP 1 LAST MATERIAL CHIP
J 0
(-4460 500);
DISPLAY 0.638298 (-4460 500);
FORCEPROP 1 LAST TOLERANCE 1%
J 0
(-4455 600);
DISPLAY 0.638298 (-4455 600);
FORCEPROP 1 LAST VALUE 1K
J 0
(-4455 650);
DISPLAY 0.638298 (-4455 650);
FORCEPROP 1 LAST PACK_TYPE 0402LF
J 0
(-4460 450);
DISPLAY 0.638298 (-4460 450);
FORCEPROP 1 LAST WATTAGE 1/16W
J 0
(-4460 550);
DISPLAY 0.638298 (-4460 550);
FORCEPROP 2 LAST CDS_LIB pure_quanta
J 0
(-4500 575);
DISPLAY INVISIBLE (-4500 575);
FORCEPROP 1 LAST PATH I57
J 0
(-4450 750);
DISPLAY 0.978723 (-4450 750);
PAINT WHITE (-4450 750);
DISPLAY INVISIBLE (-4450 750);
FORCEPROP 1 LAST PART_NUMBER CS21002FB06
J 0
(-4460 400);
DISPLAY 0.638298 (-4460 400);
DISPLAY INVISIBLE (-4460 400);
FORCEADD Q_RES..2
(-4250 575);
FORCEPROP 1 LAST LOCATION R1242
J 0
(-4205 700);
DISPLAY 0.638298 (-4205 700);
FORCEPROP 0 LAST $SEC 1
J 0
(-4200 750);
DISPLAY 0.680851 (-4200 750);
PAINT MONO (-4200 750);
DISPLAY INVISIBLE (-4200 750);
FORCEPROP 0 LAST CDS_SEC 1
J 0
(-4200 750);
DISPLAY 1.021277 (-4200 750);
DISPLAY INVISIBLE (-4200 750);
FORCEPROP 1 LASTPIN (-4250 675) $PN 1
J 0
(-4245 637);
DISPLAY 0.787234 (-4245 637);
PAINT MONO (-4245 637);
FORCEPROP 1 LASTPIN (-4250 475) $PN 2
J 0
(-4245 485);
DISPLAY 0.787234 (-4245 485);
PAINT MONO (-4245 485);
FORCEPROP 1 LAST PACK_TYPE 0402LF
J 0
(-4210 450);
DISPLAY 0.638298 (-4210 450);
FORCEPROP 1 LAST TOLERANCE 1%
J 0
(-4205 600);
DISPLAY 0.638298 (-4205 600);
FORCEPROP 1 LAST VALUE 1K
J 0
(-4205 650);
DISPLAY 0.638298 (-4205 650);
FORCEPROP 1 LAST WATTAGE 1/16W
J 0
(-4210 550);
DISPLAY 0.638298 (-4210 550);
FORCEPROP 1 LAST MATERIAL CHIP
J 0
(-4210 500);
DISPLAY 0.638298 (-4210 500);
FORCEPROP 0 LAST ROOM ADC_TI_BOM1
J 0
(-4200 750);
DISPLAY 0.680851 (-4200 750);
PAINT RED (-4200 750);
FORCEPROP 2 LAST CDS_LIB pure_quanta
J 0
(-4250 575);
DISPLAY INVISIBLE (-4250 575);
FORCEPROP 1 LAST PATH I58
J 0
(-4200 750);
DISPLAY 0.978723 (-4200 750);
PAINT WHITE (-4200 750);
DISPLAY INVISIBLE (-4200 750);
FORCEPROP 1 LAST PART_NUMBER CS21002FB06
J 0
(-4210 400);
DISPLAY 0.638298 (-4210 400);
DISPLAY INVISIBLE (-4210 400);
FORCEADD Q_RES..2
(-4500 1175);
FORCEPROP 1 LAST LOCATION R1239
J 0
(-4455 1300);
DISPLAY 0.638298 (-4455 1300);
FORCEPROP 0 LAST $SEC 1
J 0
(-4450 1350);
DISPLAY 0.680851 (-4450 1350);
PAINT MONO (-4450 1350);
DISPLAY INVISIBLE (-4450 1350);
FORCEPROP 0 LAST CDS_SEC 1
J 0
(-4450 1350);
DISPLAY 1.021277 (-4450 1350);
DISPLAY INVISIBLE (-4450 1350);
FORCEPROP 1 LASTPIN (-4500 1275) $PN 1
J 0
(-4495 1237);
DISPLAY 0.787234 (-4495 1237);
PAINT MONO (-4495 1237);
FORCEPROP 1 LASTPIN (-4500 1075) $PN 2
J 0
(-4495 1085);
DISPLAY 0.787234 (-4495 1085);
PAINT MONO (-4495 1085);
FORCEPROP 0 LAST ROOM ADC_TI_BOM1
J 0
(-4575 1350);
DISPLAY 0.553191 (-4575 1350);
PAINT RED (-4575 1350);
FORCEPROP 1 LAST MATERIAL EMPTY
J 0
(-4460 1100);
DISPLAY 0.638298 (-4460 1100);
PAINT RED (-4460 1100);
FORCEPROP 1 LAST PACK_TYPE 0402LF
J 0
(-4460 1050);
DISPLAY 0.638298 (-4460 1050);
FORCEPROP 1 LAST VALUE 1K
J 0
(-4455 1250);
DISPLAY 0.638298 (-4455 1250);
FORCEPROP 1 LAST TOLERANCE 1%
J 0
(-4455 1200);
DISPLAY 0.638298 (-4455 1200);
FORCEPROP 1 LAST WATTAGE 1/16W
J 0
(-4460 1150);
DISPLAY 0.638298 (-4460 1150);
FORCEPROP 2 LAST CDS_LIB pure_quanta
J 0
(-4500 1175);
DISPLAY INVISIBLE (-4500 1175);
FORCEPROP 1 LAST PATH I59
J 0
(-4450 1350);
DISPLAY 0.978723 (-4450 1350);
PAINT WHITE (-4450 1350);
DISPLAY INVISIBLE (-4450 1350);
FORCEPROP 1 LAST PART_NUMBER CS21002FB06
J 0
(-4460 1000);
DISPLAY 0.638298 (-4460 1000);
DISPLAY INVISIBLE (-4460 1000);
FORCEADD Q_RES..2
(-4250 1175);
FORCEPROP 1 LAST LOCATION R1241
J 0
(-4205 1300);
DISPLAY 0.638298 (-4205 1300);
FORCEPROP 0 LAST $SEC 1
J 0
(-4200 1350);
DISPLAY 0.680851 (-4200 1350);
PAINT MONO (-4200 1350);
DISPLAY INVISIBLE (-4200 1350);
FORCEPROP 0 LAST CDS_SEC 1
J 0
(-4200 1350);
DISPLAY 1.021277 (-4200 1350);
DISPLAY INVISIBLE (-4200 1350);
FORCEPROP 1 LASTPIN (-4250 1275) $PN 1
J 0
(-4245 1237);
DISPLAY 0.787234 (-4245 1237);
PAINT MONO (-4245 1237);
FORCEPROP 1 LASTPIN (-4250 1075) $PN 2
J 0
(-4245 1085);
DISPLAY 0.787234 (-4245 1085);
PAINT MONO (-4245 1085);
FORCEPROP 1 LAST MATERIAL EMPTY
J 0
(-4210 1100);
DISPLAY 0.638298 (-4210 1100);
PAINT RED (-4210 1100);
FORCEPROP 1 LAST PACK_TYPE 0402LF
J 0
(-4210 1050);
DISPLAY 0.638298 (-4210 1050);
FORCEPROP 1 LAST TOLERANCE 1%
J 0
(-4205 1200);
DISPLAY 0.638298 (-4205 1200);
FORCEPROP 1 LAST WATTAGE 1/16W
J 0
(-4210 1150);
DISPLAY 0.638298 (-4210 1150);
FORCEPROP 1 LAST VALUE 1K
J 0
(-4205 1250);
DISPLAY 0.638298 (-4205 1250);
FORCEPROP 0 LAST ROOM ADC_TI_BOM1
J 0
(-4200 1350);
DISPLAY 0.680851 (-4200 1350);
PAINT RED (-4200 1350);
FORCEPROP 2 LAST CDS_LIB pure_quanta
J 0
(-4250 1175);
DISPLAY INVISIBLE (-4250 1175);
FORCEPROP 1 LAST PATH I60
J 0
(-4200 1350);
DISPLAY 0.978723 (-4200 1350);
PAINT WHITE (-4200 1350);
DISPLAY INVISIBLE (-4200 1350);
FORCEPROP 1 LAST PART_NUMBER CS21002FB06
J 0
(-4210 1000);
DISPLAY 0.638298 (-4210 1000);
DISPLAY INVISIBLE (-4210 1000);
FORCEADD UNIVERSAL_POWER..1
(-4500 1575);
FORCEPROP 3 LASTPIN (-4500 1525) SIG_NAME P3V3_AUX\g
J 0
(-4490 1535);
DISPLAY 0.659574 (-4490 1535);
PAINT MONO (-4490 1535);
DISPLAY INVISIBLE (-4490 1535);
FORCEPROP 1 LAST HDL_POWER P3V3_AUX
J 1
(-4500 1625);
DISPLAY 0.872340 (-4500 1625);
PAINT GREEN (-4500 1625);
FORCEPROP 2 LAST CDS_LIB pure_quanta_power
J 0
(-4500 1575);
PAINT MONO (-4500 1575);
DISPLAY INVISIBLE (-4500 1575);
FORCEPROP 1 LAST PATH I61
J 0
(-4450 1600);
DISPLAY 0.872340 (-4450 1600);
PAINT AQUA (-4450 1600);
DISPLAY INVISIBLE (-4450 1600);
FORCEADD UNIVERSAL_POWER..1
(-4600 2800);
FORCEPROP 3 LASTPIN (-4600 2750) SIG_NAME P3V3_AUX\g
J 0
(-4590 2760);
DISPLAY 0.659574 (-4590 2760);
PAINT MONO (-4590 2760);
DISPLAY INVISIBLE (-4590 2760);
FORCEPROP 1 LAST HDL_POWER P3V3_AUX
J 1
(-4600 2850);
DISPLAY 0.872340 (-4600 2850);
PAINT GREEN (-4600 2850);
FORCEPROP 2 LAST CDS_LIB pure_quanta_power
J 0
(-4600 2800);
DISPLAY INVISIBLE (-4600 2800);
FORCEPROP 1 LAST PATH I66
J 0
(-4550 2825);
DISPLAY 0.872340 (-4550 2825);
PAINT AQUA (-4550 2825);
DISPLAY INVISIBLE (-4550 2825);
FORCEADD UNIVERSAL_GND..1
(-4125 2025);
FORCEPROP 3 LASTPIN (-4125 2075) SIG_NAME GND\g
J 0
(-4115 2085);
DISPLAY 0.659574 (-4115 2085);
PAINT MONO (-4115 2085);
DISPLAY INVISIBLE (-4115 2085);
FORCEPROP 2 LAST CDS_LIB pure_quanta_power
J 0
(-4125 2025);
DISPLAY INVISIBLE (-4125 2025);
FORCEPROP 1 LAST HDL_POWER GND
J 1
(-4100 1950);
DISPLAY 0.872340 (-4100 1950);
PAINT GREEN (-4100 1950);
DISPLAY INVISIBLE (-4100 1950);
FORCEPROP 1 LAST PATH I67
J 0
(-4050 2025);
DISPLAY 0.872340 (-4050 2025);
PAINT AQUA (-4050 2025);
DISPLAY INVISIBLE (-4050 2025);
FORCEADD Q_CAP..1
R 2
(-4125 2350);
FORCEPROP 1 LAST LOCATION C1094
J 2
(-3900 2475);
DISPLAY 0.978723 (-3900 2475);
FORCEPROP 0 LAST $SEC 1
J 0
(-4025 2500);
DISPLAY 0.680851 (-4025 2500);
PAINT MONO (-4025 2500);
DISPLAY INVISIBLE (-4025 2500);
FORCEPROP 0 LAST CDS_SEC 1
J 0
(-4025 2500);
DISPLAY 1.021277 (-4025 2500);
DISPLAY INVISIBLE (-4025 2500);
FORCEPROP 1 LASTPIN (-4125 2450) $PN 1
J 2
(-4135 2430);
DISPLAY 0.787234 (-4135 2430);
PAINT MONO (-4135 2430);
FORCEPROP 1 LASTPIN (-4125 2250) $PN 2
J 2
(-4135 2230);
DISPLAY 0.787234 (-4135 2230);
PAINT MONO (-4135 2230);
FORCEPROP 1 LAST PACK_TYPE 0402
J 2
(-3950 2175);
DISPLAY 0.510638 (-3950 2175);
FORCEPROP 1 LAST TOLERANCE 10%
J 2
(-3975 2325);
DISPLAY 0.510638 (-3975 2325);
FORCEPROP 1 LAST VALUE 0.1UF
J 2
(-3950 2425);
DISPLAY 0.510638 (-3950 2425);
FORCEPROP 1 LAST MATERIAL X7R
J 2
(-3975 2275);
DISPLAY 0.510638 (-3975 2275);
PAINT RED (-3975 2275);
FORCEPROP 0 LAST ROOM ADC_TI_BOM1
J 0
(-4100 2125);
DISPLAY 0.553191 (-4100 2125);
PAINT RED (-4100 2125);
FORCEPROP 1 LAST VOLTAGE 25V
J 2
(-3975 2375);
DISPLAY 0.510638 (-3975 2375);
FORCEPROP 2 LAST CDS_LIB pure_quanta
J 0
(-4125 2350);
DISPLAY INVISIBLE (-4125 2350);
FORCEPROP 1 LAST PATH I68
J 2
(-4175 2500);
DISPLAY 0.978723 (-4175 2500);
PAINT WHITE (-4175 2500);
DISPLAY INVISIBLE (-4175 2500);
FORCEPROP 1 LAST PART_NUMBER CH4104K1B00
J 2
(-3825 2225);
DISPLAY 0.510638 (-3825 2225);
DISPLAY INVISIBLE (-3825 2225);
FORCEADD Q_INDUCTOR..1
(-4300 2575);
FORCEPROP 1 LAST LOCATION L25
J 0
(-4425 2735);
DISPLAY 0.723404 (-4425 2735);
PAINT GREEN (-4425 2735);
FORCEPROP 0 LAST $SEC 1
J 0
(-4400 2850);
DISPLAY 0.680851 (-4400 2850);
PAINT MONO (-4400 2850);
DISPLAY INVISIBLE (-4400 2850);
FORCEPROP 0 LAST CDS_SEC 1
J 0
(-4400 2850);
DISPLAY 1.021277 (-4400 2850);
DISPLAY INVISIBLE (-4400 2850);
FORCEPROP 0 LASTPIN (-4400 2550) $PN 1
J 2
(-4410 2560);
DISPLAY 0.680851 (-4410 2560);
PAINT MONO (-4410 2560);
FORCEPROP 0 LASTPIN (-4200 2550) $PN 2
J 0
(-4190 2560);
DISPLAY 0.680851 (-4190 2560);
PAINT MONO (-4190 2560);
FORCEPROP 2 LAST PACK_TYPE SMLF
J 0
(-4400 2775);
DISPLAY 0.510638 (-4400 2775);
FORCEPROP 1 LAST MATERIAL IND
J 0
(-4400 2630);
DISPLAY 0.382979 (-4400 2630);
PAINT RED (-4400 2630);
FORCEPROP 2 LAST VALUE BLM18PG300SN1D 
J 0
(-4400 2825);
DISPLAY 0.510638 (-4400 2825);
FORCEPROP 0 LAST ROOM ADC_TI_BOM1
J 0
(-4400 2900);
DISPLAY 0.680851 (-4400 2900);
PAINT RED (-4400 2900);
FORCEPROP 2 LAST CDS_LIB pure_quanta
J 0
(-4300 2575);
DISPLAY INVISIBLE (-4300 2575);
FORCEPROP 1 LAST NEEDS_NO_SIZE TRUE
J 0
(-4300 2575);
DISPLAY 0.468085 (-4300 2575);
PAINT GREEN (-4300 2575);
DISPLAY INVISIBLE (-4300 2575);
FORCEPROP 1 LAST PATH I69
J 0
(-4225 2630);
DISPLAY 0.723404 (-4225 2630);
PAINT GREEN (-4225 2630);
DISPLAY INVISIBLE (-4225 2630);
FORCEPROP 1 LAST PART_NUMBER TMP_QCX8PG300001
J 0
(-4400 2685);
DISPLAY 0.382979 (-4400 2685);
PAINT GREEN (-4400 2685);
DISPLAY INVISIBLE (-4400 2685);
FORCEADD Q_CAP..1
R 2
(-7975 4025);
FORCEPROP 1 LAST LOCATION C1092
J 2
(-7775 4150);
DISPLAY 0.638298 (-7775 4150);
FORCEPROP 0 LAST $SEC 1
J 0
(-7875 4175);
DISPLAY 0.680851 (-7875 4175);
PAINT MONO (-7875 4175);
DISPLAY INVISIBLE (-7875 4175);
FORCEPROP 0 LAST CDS_SEC 1
J 0
(-7875 4175);
DISPLAY 1.021277 (-7875 4175);
DISPLAY INVISIBLE (-7875 4175);
FORCEPROP 1 LASTPIN (-7975 4125) $PN 1
J 2
(-7985 4105);
DISPLAY 0.787234 (-7985 4105);
PAINT MONO (-7985 4105);
FORCEPROP 1 LASTPIN (-7975 3925) $PN 2
J 2
(-7985 3905);
DISPLAY 0.787234 (-7985 3905);
PAINT MONO (-7985 3905);
FORCEPROP 1 LAST VOLTAGE 25V
J 2
(-7825 4050);
DISPLAY 0.510638 (-7825 4050);
FORCEPROP 1 LAST VALUE 0.1UF
J 2
(-7800 4100);
DISPLAY 0.510638 (-7800 4100);
FORCEPROP 1 LAST MATERIAL X7R
J 2
(-7825 3950);
DISPLAY 0.510638 (-7825 3950);
PAINT RED (-7825 3950);
FORCEPROP 1 LAST TOLERANCE 10%
J 2
(-7825 4000);
DISPLAY 0.510638 (-7825 4000);
FORCEPROP 1 LAST PACK_TYPE 0402
J 2
(-7800 3850);
DISPLAY 0.510638 (-7800 3850);
FORCEPROP 0 LAST ROOM ADC_TI_BOM1
J 0
(-7975 3800);
DISPLAY 0.553191 (-7975 3800);
PAINT RED (-7975 3800);
FORCEPROP 2 LAST CDS_LIB pure_quanta
J 0
(-7975 4025);
DISPLAY INVISIBLE (-7975 4025);
FORCEPROP 1 LAST PATH I76
J 2
(-8025 4175);
DISPLAY 0.978723 (-8025 4175);
PAINT WHITE (-8025 4175);
DISPLAY INVISIBLE (-8025 4175);
FORCEPROP 1 LAST PART_NUMBER CH4104K1B00
J 2
(-7675 3900);
DISPLAY 0.510638 (-7675 3900);
DISPLAY INVISIBLE (-7675 3900);
FORCEADD Q_CAP..1
(-7625 4025);
FORCEPROP 1 LAST LOCATION C1084
J 0
(-7575 4125);
DISPLAY 0.510638 (-7575 4125);
FORCEPROP 2 LAST $SEC 1
J 0
(-7575 4225);
DISPLAY 0.680851 (-7575 4225);
PAINT MONO (-7575 4225);
DISPLAY INVISIBLE (-7575 4225);
FORCEPROP 0 LAST CDS_SEC 1
J 0
(-7575 4200);
DISPLAY 1.021277 (-7575 4200);
DISPLAY INVISIBLE (-7575 4200);
FORCEPROP 1 LASTPIN (-7625 4125) $PN 1
J 0
(-7615 4105);
DISPLAY 0.787234 (-7615 4105);
PAINT MONO (-7615 4105);
FORCEPROP 1 LASTPIN (-7625 3925) $PN 2
J 0
(-7615 3905);
DISPLAY 0.787234 (-7615 3905);
PAINT MONO (-7615 3905);
FORCEPROP 1 LAST TOLERANCE 5%
J 0
(-7575 3975);
DISPLAY 0.510638 (-7575 3975);
FORCEPROP 1 LAST VOLTAGE 50V
J 0
(-7575 4025);
DISPLAY 0.510638 (-7575 4025);
FORCEPROP 1 LAST VALUE 100PF
J 0
(-7575 4075);
DISPLAY 0.510638 (-7575 4075);
FORCEPROP 1 LAST PACK_TYPE 0402
J 0
(-7575 3825);
DISPLAY 0.510638 (-7575 3825);
FORCEPROP 1 LAST MATERIAL EMPTY
J 0
(-7575 3925);
DISPLAY 0.510638 (-7575 3925);
FORCEPROP 0 LAST ROOM ADC_MAM_BOM2
J 0
(-7575 3775);
DISPLAY 0.553191 (-7575 3775);
PAINT RED (-7575 3775);
FORCEPROP 2 LAST CDS_LIB pure_quanta
J 0
(-7625 4025);
DISPLAY INVISIBLE (-7625 4025);
FORCEPROP 1 LAST PATH I77
J 0
(-7575 4175);
DISPLAY 0.978723 (-7575 4175);
PAINT WHITE (-7575 4175);
DISPLAY INVISIBLE (-7575 4175);
FORCEPROP 1 LAST PART_NUMBER CH11006JB18
J 0
(-7575 3875);
DISPLAY 0.510638 (-7575 3875);
DISPLAY INVISIBLE (-7575 3875);
FORCEADD OFFPAGE..2
(-7525 4300);
FORCEPROP 2 LAST $XR0 259 
J 0
(-7336 4300);
DISPLAY 0.638298 (-7336 4300);
PAINT MONO (-7336 4300);
FORCEPROP 2 LAST CDS_LIB standard
J 0
(-7525 4300);
DISPLAY INVISIBLE (-7525 4300);
FORCEPROP 1 LAST OFFPAGE TRUE
J 0
(-7200 4175);
DISPLAY 0.872340 (-7200 4175);
DISPLAY INVISIBLE (-7200 4175);
FORCEPROP 1 LAST COMMENT_BODY TRUE
J 0
(-7570 4205);
DISPLAY 0.872340 (-7570 4205);
PAINT GREEN (-7570 4205);
DISPLAY INVISIBLE (-7570 4205);
FORCEPROP 2 LAST PATH I78
J 0
(-7325 4350);
DISPLAY 0.680851 (-7325 4350);
DISPLAY INVISIBLE (-7325 4350);
FORCEADD OFFPAGE..2
(-7525 4450);
FORCEPROP 2 LAST $XR0 259 
J 0
(-7336 4450);
DISPLAY 0.638298 (-7336 4450);
PAINT MONO (-7336 4450);
FORCEPROP 2 LAST CDS_LIB standard
J 0
(-7525 4450);
DISPLAY INVISIBLE (-7525 4450);
FORCEPROP 1 LAST OFFPAGE TRUE
J 0
(-7200 4325);
DISPLAY 0.872340 (-7200 4325);
DISPLAY INVISIBLE (-7200 4325);
FORCEPROP 1 LAST COMMENT_BODY TRUE
J 0
(-7570 4355);
DISPLAY 0.872340 (-7570 4355);
PAINT GREEN (-7570 4355);
DISPLAY INVISIBLE (-7570 4355);
FORCEPROP 2 LAST PATH I79
J 0
(-7325 4500);
DISPLAY 0.680851 (-7325 4500);
DISPLAY INVISIBLE (-7325 4500);
FORCEADD UNIVERSAL_GND..1
(-9025 5175);
FORCEPROP 3 LASTPIN (-9025 5225) SIG_NAME GND\g
J 0
(-9015 5235);
DISPLAY 0.659574 (-9015 5235);
PAINT MONO (-9015 5235);
DISPLAY INVISIBLE (-9015 5235);
FORCEPROP 2 LAST CDS_LIB pure_quanta_power
J 0
(-9025 5175);
DISPLAY INVISIBLE (-9025 5175);
FORCEPROP 1 LAST HDL_POWER GND
J 1
(-9000 5100);
DISPLAY 0.872340 (-9000 5100);
PAINT GREEN (-9000 5100);
DISPLAY INVISIBLE (-9000 5100);
FORCEPROP 1 LAST PATH I9
J 0
(-8950 5175);
DISPLAY 0.872340 (-8950 5175);
PAINT AQUA (-8950 5175);
DISPLAY INVISIBLE (-8950 5175);
FORCEADD DNS..2
(-5900 5750);
PAINT RED (-5900 5750);
FORCEPROP 2 LAST CDS_LIB mstr_misc
J 0
(-5900 5750);
DISPLAY INVISIBLE (-5900 5750);
FORCEPROP 1 LAST COMMENT_BODY TRUE
J 0
(-5900 5750);
DISPLAY INVISIBLE (-5900 5750);
FORCEADD DNS..2
(-4500 1150);
PAINT RED (-4500 1150);
FORCEPROP 2 LAST CDS_LIB mstr_misc
J 0
(-4500 1150);
PAINT MONO (-4500 1150);
DISPLAY INVISIBLE (-4500 1150);
FORCEPROP 1 LAST COMMENT_BODY TRUE
J 0
(-4500 1150);
DISPLAY INVISIBLE (-4500 1150);
FORCEADD DNS..2
(-2325 3525);
PAINT RED (-2325 3525);
FORCEPROP 2 LAST CDS_LIB mstr_misc
J 0
(-2325 3525);
DISPLAY INVISIBLE (-2325 3525);
FORCEPROP 1 LAST COMMENT_BODY TRUE
J 0
(-2325 3525);
DISPLAY INVISIBLE (-2325 3525);
FORCEADD DNS..2
(-3400 1850);
PAINT RED (-3400 1850);
FORCEPROP 2 LAST CDS_LIB mstr_misc
J 0
(-3400 1850);
DISPLAY INVISIBLE (-3400 1850);
FORCEPROP 1 LAST COMMENT_BODY TRUE
J 0
(-3400 1850);
DISPLAY INVISIBLE (-3400 1850);
FORCEADD DNS..2
(-5950 1275);
PAINT RED (-5950 1275);
FORCEPROP 2 LAST CDS_LIB mstr_misc
J 0
(-5950 1275);
DISPLAY INVISIBLE (-5950 1275);
FORCEPROP 1 LAST COMMENT_BODY TRUE
J 0
(-5950 1275);
DISPLAY INVISIBLE (-5950 1275);
FORCEADD DNS..2
(-7600 4025);
PAINT RED (-7600 4025);
FORCEPROP 2 LAST CDS_LIB mstr_misc
J 0
(-7600 4025);
DISPLAY INVISIBLE (-7600 4025);
FORCEPROP 1 LAST COMMENT_BODY TRUE
J 0
(-7600 4025);
DISPLAY INVISIBLE (-7600 4025);
FORCEADD DNS..2
(-7500 2575);
PAINT RED (-7500 2575);
FORCEPROP 2 LAST CDS_LIB mstr_misc
J 0
(-7500 2575);
DISPLAY INVISIBLE (-7500 2575);
FORCEPROP 1 LAST COMMENT_BODY TRUE
J 0
(-7500 2575);
DISPLAY INVISIBLE (-7500 2575);
FORCEADD DNS..2
(-8225 2975);
PAINT RED (-8225 2975);
FORCEPROP 2 LAST CDS_LIB mstr_misc
J 0
(-8225 2975);
DISPLAY INVISIBLE (-8225 2975);
FORCEPROP 1 LAST COMMENT_BODY TRUE
J 0
(-8225 2975);
DISPLAY INVISIBLE (-8225 2975);
FORCEADD DNS..2
(-2350 4725);
PAINT RED (-2350 4725);
FORCEPROP 2 LAST CDS_LIB mstr_misc
J 0
(-2350 4725);
DISPLAY INVISIBLE (-2350 4725);
FORCEPROP 1 LAST COMMENT_BODY TRUE
J 0
(-2350 4725);
DISPLAY INVISIBLE (-2350 4725);
FORCEADD CAD_NOTE..1
(-3475 3350);
FORCEPROP 0 LAST S1 POP U51, AND DE-POP U50 WHICH IS 2ND SOLUTION
J 0
(-3625 3200);
DISPLAY 1.021277 (-3625 3200);
PAINT SKYBLUE (-3625 3200);
FORCEPROP 2 LAST CDS_LIB pure_quanta_power
J 0
(-3475 3350);
DISPLAY INVISIBLE (-3475 3350);
FORCEPROP 1 LAST COMMENT_BODY TRUE
J 0
(-3450 3450);
DISPLAY 0.978723 (-3450 3450);
DISPLAY INVISIBLE (-3450 3450);
FORCEADD DNS..2
(-7675 5350);
PAINT RED (-7675 5350);
FORCEPROP 2 LAST CDS_LIB mstr_misc
J 0
(-7675 5350);
DISPLAY INVISIBLE (-7675 5350);
FORCEPROP 1 LAST COMMENT_BODY TRUE
J 0
(-7675 5350);
DISPLAY INVISIBLE (-7675 5350);
FORCEADD DNS..2
(-5400 2400);
PAINT RED (-5400 2400);
FORCEPROP 2 LAST CDS_LIB mstr_misc
J 0
(-5400 2400);
DISPLAY INVISIBLE (-5400 2400);
FORCEPROP 1 LAST COMMENT_BODY TRUE
J 0
(-5400 2400);
DISPLAY INVISIBLE (-5400 2400);
FORCEADD DNS..2
(-5225 875);
PAINT RED (-5225 875);
FORCEPROP 2 LAST CDS_LIB mstr_misc
J 0
(-5225 875);
DISPLAY INVISIBLE (-5225 875);
FORCEPROP 1 LAST COMMENT_BODY TRUE
J 0
(-5225 875);
DISPLAY INVISIBLE (-5225 875);
FORCEADD DNS..2
(-8325 4450);
PAINT RED (-8325 4450);
FORCEPROP 2 LAST CDS_LIB mstr_misc
J 0
(-8325 4450);
DISPLAY INVISIBLE (-8325 4450);
FORCEPROP 1 LAST COMMENT_BODY TRUE
J 0
(-8325 4450);
DISPLAY INVISIBLE (-8325 4450);
FORCEADD DNS..2
(-8375 5775);
PAINT RED (-8375 5775);
FORCEPROP 2 LAST CDS_LIB mstr_misc
J 0
(-8375 5775);
DISPLAY INVISIBLE (-8375 5775);
FORCEPROP 1 LAST COMMENT_BODY TRUE
J 0
(-8375 5775);
DISPLAY INVISIBLE (-8375 5775);
FORCEADD DNS..2
(-4925 5375);
PAINT RED (-4925 5375);
FORCEPROP 2 LAST CDS_LIB mstr_misc
J 0
(-4925 5375);
DISPLAY INVISIBLE (-4925 5375);
FORCEPROP 1 LAST COMMENT_BODY TRUE
J 0
(-4925 5375);
DISPLAY INVISIBLE (-4925 5375);
FORCEADD DNS..2
(-8175 1375);
PAINT RED (-8175 1375);
FORCEPROP 2 LAST CDS_LIB mstr_misc
J 0
(-8175 1375);
DISPLAY INVISIBLE (-8175 1375);
FORCEPROP 1 LAST COMMENT_BODY TRUE
J 0
(-8175 1375);
DISPLAY INVISIBLE (-8175 1375);
FORCEADD DNS..2
(-6025 4225);
PAINT RED (-6025 4225);
FORCEPROP 2 LAST CDS_LIB mstr_misc
J 0
(-6025 4225);
DISPLAY INVISIBLE (-6025 4225);
FORCEPROP 1 LAST COMMENT_BODY TRUE
J 0
(-6025 4225);
DISPLAY INVISIBLE (-6025 4225);
FORCEADD DNS..2
(-4250 1150);
PAINT RED (-4250 1150);
FORCEPROP 2 LAST CDS_LIB mstr_misc
J 0
(-4250 1150);
PAINT MONO (-4250 1150);
DISPLAY INVISIBLE (-4250 1150);
FORCEPROP 1 LAST COMMENT_BODY TRUE
J 0
(-4250 1150);
DISPLAY INVISIBLE (-4250 1150);
FORCEADD DNS..2
(-7275 975);
PAINT RED (-7275 975);
FORCEPROP 2 LAST CDS_LIB mstr_misc
J 0
(-7275 975);
DISPLAY INVISIBLE (-7275 975);
FORCEPROP 1 LAST COMMENT_BODY TRUE
J 0
(-7275 975);
DISPLAY INVISIBLE (-7275 975);
FORCEADD DNS..2
(-6125 2800);
PAINT RED (-6125 2800);
FORCEPROP 2 LAST CDS_LIB mstr_misc
J 0
(-6125 2800);
DISPLAY INVISIBLE (-6125 2800);
FORCEPROP 1 LAST COMMENT_BODY TRUE
J 0
(-6125 2800);
DISPLAY INVISIBLE (-6125 2800);
FORCEADD DNS..2
(-5175 3825);
PAINT RED (-5175 3825);
FORCEPROP 2 LAST CDS_LIB mstr_misc
J 0
(-5175 3825);
DISPLAY INVISIBLE (-5175 3825);
FORCEPROP 1 LAST COMMENT_BODY TRUE
J 0
(-5175 3825);
DISPLAY INVISIBLE (-5175 3825);
FORCEADD QUANTA_TITLE_BLOCK_C..1
(0 0);
FORCEPROP 0 LAST CDS_CON_LAST_MODIFIED Thu Sep 14 16:13:11 2023
J 0
(-1885 15);
DISPLAY INVISIBLE (-1885 15);
FORCEPROP 1 LAST CUSTOM_TXT_CDS <CON_LAST_MODIFIED>
J 0
(-1885 15);
DISPLAY 0.978723 (-1885 15);
FORCEPROP 2 LAST CUSTOM_TXT_CDS <XR_PAGE_TITLE>
J 0
(-7890 5250);
DISPLAY 0.638298 (-7890 5250);
PAINT PINK (-7890 5250);
DISPLAY INVISIBLE (-7890 5250);
FORCEPROP 1 LAST CUSTOM_TXT_CDS <NAME_2>
J 0
(-3175 50);
FORCEPROP 1 LAST CUSTOM_TXT_CDS <NAME_1>
J 0
(-3175 175);
FORCEPROP 1 LAST CUSTOM_TXT_CDS <Q_NUMBER>
J 0
(-1403 103);
DISPLAY 1.212766 (-1403 103);
FORCEPROP 1 LAST CUSTOM_TXT_CDS <Q_PROJ>
J 0
(-2382 102);
DISPLAY 1.212766 (-2382 102);
FORCEPROP 1 LAST CUSTOM_TXT_CDS <Q_REV>
J 0
(-184 103);
DISPLAY 1.212766 (-184 103);
FORCEPROP 1 LAST CUSTOM_TXT_CDS <CON_PAGE_NUM> OF <CON_TOTAL_PAGES>
J 0
(-446 18);
DISPLAY 0.978723 (-446 18);
FORCEPROP 1 LAST Q_TITLE VOLTAGE SENSOR (2/2)
J 0
(-9366 26);
DISPLAY 2.446809 (-9366 26);
PAINT GREEN (-9366 26);
FORCEPROP 2 LAST CDS_LIB pure_quanta
J 0
(0 0);
DISPLAY INVISIBLE (0 0);
FORCEPROP 1 LAST CDS_LMAN_SYM_OUTLINE -9475,6775,100,-125
J 0
(0 0);
DISPLAY 0.468085 (0 0);
PAINT GREEN (0 0);
DISPLAY INVISIBLE (0 0);
FORCEPROP 2 LAST PAGE_BORDER TRUE
J 0
(-7890 5250);
DISPLAY 0.638298 (-7890 5250);
PAINT PINK (-7890 5250);
DISPLAY INVISIBLE (-7890 5250);
FORCEPROP 2 LAST CDS_XR_PAGE_TITLE CR-259 : @T6G_MB_LIB.T6G(SCH_1):PAGE259
J 0
(-7890 5250);
DISPLAY 0.638298 (-7890 5250);
PAINT PINK (-7890 5250);
DISPLAY INVISIBLE (-7890 5250);
FORCEPROP 1 LAST Q_DEPT BU9
J 1
(-3763 49);
DISPLAY 1.957447 (-3763 49);
PAINT GREEN (-3763 49);
DISPLAY INVISIBLE (-3763 49);
FORCEPROP 1 LAST COMMENT_BODY TRUE
J 0
(12 -13);
DISPLAY 0.978723 (12 -13);
PAINT GREEN (12 -13);
DISPLAY INVISIBLE (12 -13);
FORCEADD DNS..2
(-3425 2325);
PAINT RED (-3425 2325);
FORCEPROP 2 LAST CDS_LIB mstr_misc
J 0
(-3425 2325);
DISPLAY INVISIBLE (-3425 2325);
FORCEPROP 1 LAST COMMENT_BODY TRUE
J 0
(-3425 2325);
DISPLAY INVISIBLE (-3425 2325);
WIRE 16 -1 (-4150 5050)(-4150 5100);
WIRE 16 -1 (-3425 1750)(-3425 1575);
WIRE 16 -1 (-9025 6125)(-9025 6225);
WIRE 16 -1 (-1175 1525)(-1000 1525);
WIRE 16 -1 (-1000 1525)(-1000 1375);
WIRE 16 -1 (-3775 5100)(-3775 5050);
WIRE 16 -1 (-1450 5050)(-1450 5075);
WIRE 16 -1 (-1075 5075)(-1075 5050);
WIRE 16 -1 (-650 5375)(-325 5375);
WIRE 16 -1 (-325 5375)(-325 5550);
WIRE 16 -1 (-8950 3325)(-8950 3425);
WIRE 16 -1 (-7525 2475)(-7525 2350);
WIRE 16 -1 (-7875 2475)(-7875 2350);
WIRE 16 -1 (-8975 4125)(-8975 4025);
WIRE 16 -1 (-8950 2400)(-8950 2600);
WIRE 16 -1 (-9025 1725)(-9025 1825);
WIRE 16 -1 (-7300 875)(-7300 750);
WIRE 16 -1 (-7825 875)(-7825 750);
WIRE 16 -1 (-9025 800)(-9025 1000);
WIRE 16 -1 (-6800 6100)(-6800 6200);
WIRE 16 -1 (-4950 5275)(-4950 5150);
WIRE 16 -1 (-8975 4900)(-8975 4800);
WIRE 16 -1 (-5550 5250)(-5550 5125);
WIRE 16 -1 (-6800 5200)(-6800 5400);
WIRE 16 -1 (-6750 4575)(-6750 4675);
WIRE 16 -1 (-5200 3725)(-5200 3600);
WIRE 16 -1 (-5675 3725)(-5675 3600);
WIRE 16 -1 (-6750 3650)(-6750 3850);
WIRE 16 -1 (-6850 3150)(-6850 3250);
WIRE 16 -1 (-5425 2300)(-5425 2175);
WIRE 16 -1 (-5775 2300)(-5775 2175);
WIRE 16 -1 (-6850 2225)(-6850 2425);
WIRE 16 -1 (-6675 1625)(-6675 1725);
WIRE 16 -1 (-5250 775)(-5250 650);
WIRE 16 -1 (-5600 775)(-5600 650);
WIRE 16 -1 (-6675 700)(-6675 900);
WIRE 16 -1 (-8050 5250)(-8050 5125);
WIRE 16 -1 (-7700 5250)(-7700 5125);
WIRE 16 -1 (-7975 3925)(-7975 3800);
WIRE 16 -1 (-7625 3925)(-7625 3800);
WIRE 16 -1 (-4250 475)(-4250 400);
WIRE 16 -1 (-4500 475)(-4500 400);
WIRE 16 -1 (-4600 2550)(-4600 2750);
WIRE 16 -1 (-4600 2550)(-4400 2550);
WIRE 16 -1 (-9025 5375)(-9025 5225);
WIRE 16 -1 (-2875 5100)(-2875 5375);
WIRE 16 -1 (-2775 5100)(-2875 5100);
WIRE 16 -1 (-2875 5375)(-3325 5375);
FORCEPROP 2 LAST SIG_NAME MAX11617_2_VREF_R
J 0
(-3035 5385);
DISPLAY 0.638298 (-3035 5385);
FORCEPROP 2 LASTPROP $XRERR UNIQUE?
J 0
(-3275 5385);
DISPLAY 0.638298 (-3275 5385);
PAINT MONO (-3275 5385);
DISPLAY INVISIBLE (-3275 5385);
WIRE 16 -1 (-2775 4800)(-2875 4800);
WIRE 16 -1 (-2875 4800)(-2875 4900);
WIRE 16 -1 (-2875 4150)(-2875 4800);
WIRE 16 -1 (-2775 4900)(-2875 4900);
WIRE 16 -1 (-2875 5000)(-2875 4900);
WIRE 16 -1 (-2775 5000)(-2875 5000);
WIRE 16 -1 (-1975 5000)(-1850 5000);
WIRE 16 -1 (-1850 4200)(-1850 5000);
WIRE 16 -1 (-1975 5100)(-1825 5100);
WIRE 16 -1 (-1825 5100)(-1825 5375);
WIRE 16 -1 (-1825 5375)(-1450 5375);
FORCEPROP 2 LAST SIG_NAME P3V3_MAX11617_2_VDD
J 0
(-1760 5385);
DISPLAY 0.510638 (-1760 5385);
FORCEPROP 2 LASTPROP $XRERR UNIQUE?
J 0
(-2000 5385);
DISPLAY 0.638298 (-2000 5385);
PAINT MONO (-2000 5385);
DISPLAY INVISIBLE (-2000 5385);
WIRE 16 -1 (-1075 5375)(-1450 5375);
WIRE 16 -1 (-1450 5275)(-1450 5375);
WIRE 16 -1 (-850 5375)(-1075 5375);
WIRE 16 -1 (-1075 5275)(-1075 5375);
WIRE 16 -1 (-4950 5475)(-4950 5750);
WIRE 16 -1 (-4900 5750)(-4950 5750);
WIRE 16 -1 (-5825 5750)(-4950 5750);
FORCEPROP 0 LAST CDS_PHYS_NET_NAME P3V3_AUX_ADC_MAM
J 0
(-5260 5798);
PAINT MONO (-5260 5798);
DISPLAY INVISIBLE (-5260 5798);
FORCEPROP 2 LAST SIG_NAME P1V8_CPU1_RT_1D_ADC_MAM
J 0
(-5585 5760);
DISPLAY 0.510638 (-5585 5760);
WIRE 16 2175 (-6200 5475)(-5600 5475);
WIRE 16 2175 (-6200 5950)(-6200 5475);
WIRE 16 2175 (-5600 5950)(-5600 5475);
WIRE 16 2175 (-6200 5950)(-5600 5950);
FORCEPROP 0 LAST M1 CO-LAYOUT
J 0
(-6100 5975);
DISPLAY 1.021277 (-6100 5975);
WIRE 16 -1 (-2775 4500)(-3575 4500);
FORCEPROP 0 LAST CDS_PHYS_NET_NAME P12V_OCP_V3_2_ISENSE_MAM
J 0
(-3085 4548);
PAINT MONO (-3085 4548);
DISPLAY INVISIBLE (-3085 4548);
FORCEPROP 2 LAST SIG_NAME P1V2_AUX_ADC_MAM
J 0
(-3485 4510);
DISPLAY 0.510638 (-3485 4510);
WIRE 16 -1 (-1050 4900)(-1975 4900);
FORCEPROP 0 LAST CDS_PHYS_NET_NAME SMB_SEN_MAM_3V3AUX_SDA
J 0
(-1360 4948);
PAINT MONO (-1360 4948);
DISPLAY INVISIBLE (-1360 4948);
FORCEPROP 2 LAST SIG_NAME SMB_SEN_MAM_2_3V3AUX_SDA
J 0
(-1710 4910);
DISPLAY 0.510638 (-1710 4910);
WIRE 16 -1 (-4625 6450)(-4150 6450);
WIRE 16 -1 (-4625 6450)(-4625 6325);
WIRE 16 -1 (-4625 6450)(-5050 6450);
WIRE 16 -1 (-4150 6450)(-3725 6450);
WIRE 16 -1 (-4150 6325)(-4150 6450);
WIRE 16 -1 (-4150 6325)(-4625 6325);
WIRE 16 -1 (-3725 6325)(-4150 6325);
WIRE 16 -1 (-4150 6200)(-4150 6325);
WIRE 16 -1 (-3725 6450)(-2950 6450);
WIRE 16 -1 (-3725 6450)(-3725 6325);
WIRE 16 -1 (-5050 6325)(-5050 6450);
WIRE 16 -1 (-5050 6450)(-5500 6450);
WIRE 16 -1 (-4625 6325)(-4625 6200);
WIRE 16 -1 (-5050 6325)(-4625 6325);
WIRE 16 -1 (-5050 6200)(-5050 6325);
WIRE 16 -1 (-5500 6325)(-5050 6325);
WIRE 16 -1 (-5050 6200)(-4625 6200);
WIRE 16 -1 (-4625 6200)(-4150 6200);
WIRE 16 -1 (-5500 6450)(-5500 6325);
WIRE 16 -1 (-3725 6325)(-2950 6325);
WIRE 16 -1 (-3725 6325)(-3725 6200);
WIRE 16 -1 (-2100 6450)(-2950 6450);
WIRE 16 -1 (-2950 6325)(-2950 6450);
WIRE 16 -1 (-4150 6200)(-3725 6200);
WIRE 16 -1 (-3725 6200)(-2950 6200);
WIRE 16 -1 (-2950 6325)(-2100 6325);
WIRE 16 -1 (-2950 6200)(-2950 6325);
WIRE 16 -1 (-1525 6450)(-2100 6450);
WIRE 16 -1 (-2100 6325)(-2100 6450);
WIRE 16 -1 (-5500 6325)(-5500 6200);
WIRE 16 -1 (-5500 6200)(-5050 6200);
WIRE 16 -1 (-2100 6325)(-1525 6325);
WIRE 16 -1 (-2100 6325)(-2100 6200);
WIRE 16 -1 (-875 6450)(-1525 6450);
WIRE 16 -1 (-1525 6450)(-1525 6325);
WIRE 16 -1 (-2950 6200)(-2100 6200);
WIRE 16 -1 (-2100 6200)(-1525 6200);
WIRE 16 -1 (-1525 6325)(-875 6325);
WIRE 16 -1 (-1525 6325)(-1525 6200);
WIRE 16 -1 (-250 6450)(-875 6450);
WIRE 16 -1 (-875 6450)(-875 6325);
WIRE 16 -1 (-875 6325)(-250 6325);
WIRE 16 -1 (-875 6325)(-875 6200);
WIRE 16 -1 (-250 6325)(-250 6450);
WIRE 16 -1 (-1525 6200)(-875 6200);
WIRE 16 -1 (-875 6200)(-250 6200);
WIRE 16 -1 (-250 6200)(-250 6325);
WIRE 16 -1 (-7525 2675)(-7525 2975);
WIRE 16 -1 (-7500 2975)(-7525 2975);
WIRE 16 -1 (-8150 2975)(-7525 2975);
FORCEPROP 0 LAST CDS_PHYS_NET_NAME P3V3_AUX_ADC_MAM
J 0
(-7585 3023);
PAINT MONO (-7585 3023);
DISPLAY INVISIBLE (-7585 3023);
FORCEPROP 2 LAST SIG_NAME P1V2_AUX_ADC_MAM
J 0
(-7910 2985);
DISPLAY 0.510638 (-7910 2985);
WIRE 16 -1 (-7875 2675)(-7875 2825);
WIRE 16 -1 (-7500 2825)(-7875 2825);
FORCEPROP 0 LAST CDS_PHYS_NET_NAME P3V3_AUX_ADC_TIC
J 0
(-7635 2873);
PAINT MONO (-7635 2873);
DISPLAY INVISIBLE (-7635 2873);
WIRE 16 -1 (-8150 2825)(-7875 2825);
FORCEPROP 2 LAST SIG_NAME P1V2_AUX_ADC_TIC
J 0
(-7910 2835);
DISPLAY 0.510638 (-7910 2835);
WIRE 16 -1 (-8100 1375)(-7300 1375);
FORCEPROP 0 LAST CDS_PHYS_NET_NAME P3V3_AUX_ADC_MAM
J 0
(-7535 1423);
PAINT MONO (-7535 1423);
DISPLAY INVISIBLE (-7535 1423);
FORCEPROP 2 LAST SIG_NAME P1V8_CPU0_RT_1D_ADC_MAM
J 0
(-7860 1385);
DISPLAY 0.510638 (-7860 1385);
WIRE 16 -1 (-7275 1375)(-7300 1375);
WIRE 16 -1 (-7300 1075)(-7300 1375);
WIRE 16 2175 (-8475 1100)(-7875 1100);
WIRE 16 2175 (-8475 1575)(-8475 1100);
WIRE 16 2175 (-7875 1575)(-7875 1100);
WIRE 16 2175 (-8475 1575)(-7875 1575);
FORCEPROP 0 LAST M1 CO-LAYOUT
J 0
(-8375 1600);
DISPLAY 1.021277 (-8375 1600);
WIRE 16 -1 (-8100 1225)(-7825 1225);
FORCEPROP 2 LAST SIG_NAME P1V8_CPU0_RT_1D_ADC_TIC
J 0
(-7860 1235);
DISPLAY 0.510638 (-7860 1235);
WIRE 16 -1 (-7250 1225)(-7825 1225);
FORCEPROP 0 LAST CDS_PHYS_NET_NAME P3V3_AUX_ADC_TIC
J 0
(-7385 1273);
PAINT MONO (-7385 1273);
DISPLAY INVISIBLE (-7385 1273);
WIRE 16 -1 (-7825 1075)(-7825 1225);
WIRE 16 2175 (-6250 1500)(-5650 1500);
FORCEPROP 0 LAST M1 CO-LAYOUT
J 0
(-6150 1525);
DISPLAY 1.021277 (-6150 1525);
WIRE 16 2175 (-6250 1500)(-6250 1000);
WIRE 16 2175 (-5650 1500)(-5650 1000);
WIRE 16 2175 (-6250 1000)(-5650 1000);
WIRE 16 -1 (-1350 3550)(-2250 3550);
FORCEPROP 0 LAST CDS_PHYS_NET_NAME SMB_SEN_MAM_3V3AUX_SDA
J 0
(-1810 3598);
PAINT MONO (-1810 3598);
DISPLAY INVISIBLE (-1810 3598);
FORCEPROP 2 LAST SIG_NAME SMB_SEN_MAM_2_3V3AUX_SDA
J 0
(-1935 3560);
DISPLAY 0.510638 (-1935 3560);
WIRE 16 -1 (-1350 3500)(-2250 3500);
FORCEPROP 0 LAST CDS_PHYS_NET_NAME SMB_SEN_MAM_3V3AUX_SCL
J 0
(-1810 3548);
PAINT MONO (-1810 3548);
DISPLAY INVISIBLE (-1810 3548);
FORCEPROP 2 LAST SIG_NAME SMB_SEN_MAM_2_3V3AUX_SCL
J 0
(-1935 3510);
DISPLAY 0.510638 (-1935 3510);
WIRE 16 -1 (-3300 3500)(-2450 3500);
FORCEPROP 0 LAST CDS_PHYS_NET_NAME SMB_SCM_2_R4_SCL
J 0
(-3260 3548);
PAINT MONO (-3260 3548);
DISPLAY INVISIBLE (-3260 3548);
FORCEPROP 2 LAST SIG_NAME SMB_ADC_SCL_R
J 0
(-3160 3510);
DISPLAY 0.680851 (-3160 3510);
WIRE 16 -1 (-1175 4400)(-1975 4400);
FORCEPROP 0 LAST CDS_PHYS_NET_NAME P3V3_ADC_MAM
J 0
(-1485 4448);
PAINT MONO (-1485 4448);
DISPLAY INVISIBLE (-1485 4448);
FORCEPROP 0 LAST SIG_NAME P1V8_CPU1_RT_1D_ADC_MAM
J 0
(-1710 4410);
DISPLAY 0.510638 (-1710 4410);
WIRE 16 -1 (-3300 3550)(-2450 3550);
FORCEPROP 0 LAST CDS_PHYS_NET_NAME SMB_SCM_2_R4_SDA
J 0
(-3260 3598);
PAINT MONO (-3260 3598);
DISPLAY INVISIBLE (-3260 3598);
FORCEPROP 2 LAST SIG_NAME SMB_ADC_SDA_R
J 0
(-3160 3560);
DISPLAY 0.680851 (-3160 3560);
WIRE 16 -1 (-1050 4800)(-1975 4800);
FORCEPROP 0 LAST CDS_PHYS_NET_NAME SMB_SEN_MAM_3V3AUX_SCL
J 0
(-1360 4848);
PAINT MONO (-1360 4848);
DISPLAY INVISIBLE (-1360 4848);
FORCEPROP 2 LAST SIG_NAME SMB_SEN_MAM_2_3V3AUX_SCL
J 0
(-1710 4810);
DISPLAY 0.510638 (-1710 4810);
WIRE 16 -1 (-5250 975)(-5250 1275);
WIRE 16 -1 (-5150 1275)(-5250 1275);
WIRE 16 -1 (-5875 1275)(-5250 1275);
FORCEPROP 0 LAST CDS_PHYS_NET_NAME P3V3_AUX_ADC_MAM
J 0
(-5310 1323);
PAINT MONO (-5310 1323);
DISPLAY INVISIBLE (-5310 1323);
FORCEPROP 2 LAST SIG_NAME PVDD18_S5_P1_ADC_MAM
J 0
(-5635 1285);
DISPLAY 0.510638 (-5635 1285);
WIRE 16 -1 (-3800 2250)(-3800 2075);
WIRE 16 -1 (-4125 2075)(-3800 2075);
WIRE 16 -1 (-4125 2250)(-4125 2075);
WIRE 16 -1 (-4500 1275)(-4500 1450);
WIRE 16 -1 (-4250 1450)(-4500 1450);
WIRE 16 -1 (-4500 1525)(-4500 1450);
WIRE 16 -1 (-4250 1275)(-4250 1450);
WIRE 16 -1 (-5600 975)(-5600 1125);
WIRE 16 -1 (-5150 1125)(-5600 1125);
FORCEPROP 0 LAST CDS_PHYS_NET_NAME P3V3_AUX_ADC_TIC
J 0
(-5285 1173);
PAINT MONO (-5285 1173);
DISPLAY INVISIBLE (-5285 1173);
WIRE 16 -1 (-5875 1125)(-5600 1125);
FORCEPROP 2 LAST SIG_NAME PVDD18_S5_P1_ADC_TIC
J 0
(-5635 1135);
DISPLAY 0.510638 (-5635 1135);
WIRE 16 -1 (-6200 1125)(-6075 1125);
WIRE 16 -1 (-6200 1275)(-6200 1125);
WIRE 16 -1 (-6200 1275)(-6075 1275);
WIRE 16 -1 (-6200 1275)(-6675 1275);
FORCEPROP 0 LAST CDS_PHYS_NET_NAME P3V3_AUX_ADC
J 0
(-6210 1323);
PAINT MONO (-6210 1323);
DISPLAY INVISIBLE (-6210 1323);
FORCEPROP 2 LAST SIG_NAME PVDD18_S5_P1_ADC
J 0
(-6635 1300);
DISPLAY 0.510638 (-6635 1300);
FORCEPROP 2 LASTPROP $XRERR UNIQUE?
J 0
(-6875 1300);
DISPLAY 0.638298 (-6875 1300);
PAINT MONO (-6875 1300);
DISPLAY INVISIBLE (-6875 1300);
WIRE 16 -1 (-6675 1425)(-6675 1275);
WIRE 16 -1 (-6675 1100)(-6675 1275);
WIRE 16 2175 (-6425 2525)(-5825 2525);
WIRE 16 2175 (-6425 3025)(-6425 2525);
WIRE 16 2175 (-5825 3025)(-5825 2525);
WIRE 16 2175 (-6425 3025)(-5825 3025);
FORCEPROP 0 LAST M1 CO-LAYOUT
J 0
(-6325 3050);
DISPLAY 1.021277 (-6325 3050);
WIRE 16 -1 (-5775 2500)(-5775 2650);
WIRE 16 -1 (-5350 2650)(-5775 2650);
FORCEPROP 0 LAST CDS_PHYS_NET_NAME P3V3_AUX_ADC_TIC
J 0
(-5485 2698);
PAINT MONO (-5485 2698);
DISPLAY INVISIBLE (-5485 2698);
WIRE 16 -1 (-6050 2650)(-5775 2650);
FORCEPROP 2 LAST SIG_NAME PVDD18_S5_P0_ADC_TIC
J 0
(-5810 2660);
DISPLAY 0.510638 (-5810 2660);
WIRE 16 -1 (-5425 2500)(-5425 2800);
WIRE 16 -1 (-5350 2800)(-5425 2800);
WIRE 16 -1 (-6050 2800)(-5425 2800);
FORCEPROP 0 LAST CDS_PHYS_NET_NAME P3V3_AUX_ADC_MAM
J 0
(-5485 2848);
PAINT MONO (-5485 2848);
DISPLAY INVISIBLE (-5485 2848);
FORCEPROP 2 LAST SIG_NAME PVDD18_S5_P0_ADC_MAM
J 0
(-5810 2810);
DISPLAY 0.510638 (-5810 2810);
WIRE 16 -1 (-6375 2650)(-6250 2650);
WIRE 16 -1 (-6375 2800)(-6375 2650);
WIRE 16 -1 (-6375 2800)(-6250 2800);
WIRE 16 -1 (-6375 2800)(-6850 2800);
FORCEPROP 0 LAST CDS_PHYS_NET_NAME P3V3_AUX_ADC
J 0
(-6385 2848);
PAINT MONO (-6385 2848);
DISPLAY INVISIBLE (-6385 2848);
FORCEPROP 2 LAST SIG_NAME PVDD18_S5_P0_ADC
J 0
(-6835 2825);
DISPLAY 0.510638 (-6835 2825);
FORCEPROP 2 LASTPROP $XRERR UNIQUE?
J 0
(-7075 2825);
DISPLAY 0.638298 (-7075 2825);
PAINT MONO (-7075 2825);
DISPLAY INVISIBLE (-7075 2825);
WIRE 16 -1 (-6850 2950)(-6850 2800);
WIRE 16 -1 (-6850 2625)(-6850 2800);
WIRE 16 -1 (-5200 3925)(-5200 4225);
WIRE 16 -1 (-5150 4225)(-5200 4225);
WIRE 16 -1 (-5950 4225)(-5200 4225);
FORCEPROP 0 LAST CDS_PHYS_NET_NAME P3V3_AUX_ADC_MAM
J 0
(-5385 4273);
PAINT MONO (-5385 4273);
DISPLAY INVISIBLE (-5385 4273);
FORCEPROP 2 LAST SIG_NAME PVDD_33_S5_ADC_MAM
J 0
(-5710 4235);
DISPLAY 0.510638 (-5710 4235);
WIRE 16 2175 (-6325 4425)(-5725 4425);
FORCEPROP 0 LAST M1 CO-LAYOUT
J 0
(-6225 4450);
DISPLAY 1.021277 (-6225 4450);
WIRE 16 2175 (-6325 4425)(-6325 3950);
WIRE 16 2175 (-5725 4425)(-5725 3950);
WIRE 16 2175 (-6325 3950)(-5725 3950);
WIRE 16 -1 (-5825 5600)(-5550 5600);
FORCEPROP 2 LAST SIG_NAME P1V8_CPU1_RT_1D_ADC_TIC
J 0
(-5585 5610);
DISPLAY 0.510638 (-5585 5610);
WIRE 16 -1 (-4875 5600)(-5550 5600);
FORCEPROP 0 LAST CDS_PHYS_NET_NAME P3V3_AUX_ADC_TIC
J 0
(-5010 5648);
PAINT MONO (-5010 5648);
DISPLAY INVISIBLE (-5010 5648);
WIRE 16 -1 (-5550 5450)(-5550 5600);
WIRE 16 -1 (-6150 5600)(-6025 5600);
WIRE 16 -1 (-6150 5750)(-6150 5600);
WIRE 16 -1 (-6150 5750)(-6025 5750);
WIRE 16 -1 (-6150 5750)(-6800 5750);
FORCEPROP 0 LAST CDS_PHYS_NET_NAME P3V3_AUX_ADC
J 0
(-6160 5798);
PAINT MONO (-6160 5798);
DISPLAY INVISIBLE (-6160 5798);
FORCEPROP 2 LAST SIG_NAME P1V8_CPU1_RT_1D_ADC
J 0
(-6735 5775);
DISPLAY 0.510638 (-6735 5775);
FORCEPROP 2 LASTPROP $XRERR UNIQUE?
J 0
(-6975 5775);
DISPLAY 0.638298 (-6975 5775);
PAINT MONO (-6975 5775);
DISPLAY INVISIBLE (-6975 5775);
WIRE 16 -1 (-6800 5900)(-6800 5750);
WIRE 16 -1 (-6800 5600)(-6800 5750);
WIRE 16 -1 (-8250 4300)(-7975 4300);
FORCEPROP 2 LAST SIG_NAME P1V8_AUX_ADC_TIC
J 0
(-8010 4310);
DISPLAY 0.510638 (-8010 4310);
WIRE 16 -1 (-7575 4300)(-7975 4300);
FORCEPROP 0 LAST CDS_PHYS_NET_NAME P3V3_ADC_TIC
J 0
(-7710 4348);
PAINT MONO (-7710 4348);
DISPLAY INVISIBLE (-7710 4348);
WIRE 16 -1 (-7975 4125)(-7975 4300);
WIRE 16 2175 (-8625 4175)(-8025 4175);
WIRE 16 2175 (-8625 4675)(-8625 4175);
WIRE 16 2175 (-8025 4675)(-8025 4175);
WIRE 16 2175 (-8625 4675)(-8025 4675);
FORCEPROP 0 LAST M1 CO-LAYOUT
J 0
(-8525 4700);
DISPLAY 1.021277 (-8525 4700);
WIRE 16 -1 (-6750 4050)(-6750 4225);
WIRE 16 -1 (-6275 4225)(-6750 4225);
FORCEPROP 0 LAST CDS_PHYS_NET_NAME P3V3_AUX_ADC
J 0
(-6285 4273);
PAINT MONO (-6285 4273);
DISPLAY INVISIBLE (-6285 4273);
FORCEPROP 2 LAST SIG_NAME PVDD_33_S5_ADC
J 0
(-6685 4250);
DISPLAY 0.510638 (-6685 4250);
FORCEPROP 2 LASTPROP $XRERR UNIQUE?
J 0
(-6925 4250);
DISPLAY 0.638298 (-6925 4250);
PAINT MONO (-6925 4250);
DISPLAY INVISIBLE (-6925 4250);
WIRE 16 -1 (-6750 4375)(-6750 4225);
WIRE 16 -1 (-6275 4225)(-6150 4225);
WIRE 16 -1 (-6275 4225)(-6275 4075);
WIRE 16 -1 (-6275 4075)(-6150 4075);
WIRE 16 -1 (-8425 1375)(-8300 1375);
WIRE 16 -1 (-8425 1375)(-8425 1225);
WIRE 16 -1 (-8425 1375)(-9025 1375);
FORCEPROP 0 LAST CDS_PHYS_NET_NAME P3V3_AUX_ADC
J 0
(-8435 1423);
PAINT MONO (-8435 1423);
DISPLAY INVISIBLE (-8435 1423);
FORCEPROP 2 LAST SIG_NAME P1V8_CPU0_RT_1D_ADC
J 0
(-8935 1400);
DISPLAY 0.510638 (-8935 1400);
FORCEPROP 2 LASTPROP $XRERR UNIQUE?
J 0
(-9175 1400);
DISPLAY 0.638298 (-9175 1400);
PAINT MONO (-9175 1400);
DISPLAY INVISIBLE (-9175 1400);
WIRE 16 -1 (-9025 1525)(-9025 1375);
WIRE 16 -1 (-9025 1200)(-9025 1375);
WIRE 16 -1 (-8425 1225)(-8300 1225);
WIRE 16 2175 (-8525 2700)(-7925 2700);
WIRE 16 2175 (-8525 3175)(-8525 2700);
WIRE 16 2175 (-7925 3175)(-7925 2700);
WIRE 16 2175 (-8525 3175)(-7925 3175);
FORCEPROP 0 LAST M1 CO-LAYOUT
J 0
(-8425 3200);
DISPLAY 1.021277 (-8425 3200);
WIRE 16 -1 (-8475 2825)(-8350 2825);
WIRE 16 -1 (-8475 2975)(-8475 2825);
WIRE 16 -1 (-8475 2975)(-8350 2975);
WIRE 16 -1 (-8475 2975)(-8950 2975);
FORCEPROP 0 LAST CDS_PHYS_NET_NAME P3V3_AUX_ADC
J 0
(-8485 3023);
PAINT MONO (-8485 3023);
DISPLAY INVISIBLE (-8485 3023);
FORCEPROP 2 LAST SIG_NAME P1V2_AUX_ADC
J 0
(-8835 2985);
DISPLAY 0.510638 (-8835 2985);
FORCEPROP 2 LASTPROP $XRERR UNIQUE?
J 0
(-9075 2985);
DISPLAY 0.638298 (-9075 2985);
PAINT MONO (-9075 2985);
DISPLAY INVISIBLE (-9075 2985);
WIRE 16 -1 (-8950 3125)(-8950 2975);
WIRE 16 -1 (-8950 2800)(-8950 2975);
WIRE 16 -1 (-7625 4125)(-7625 4450);
WIRE 16 -1 (-7575 4450)(-7625 4450);
WIRE 16 -1 (-8250 4450)(-7625 4450);
FORCEPROP 0 LAST CDS_PHYS_NET_NAME P3V3_ADC_MAM
J 0
(-7685 4498);
PAINT MONO (-7685 4498);
DISPLAY INVISIBLE (-7685 4498);
FORCEPROP 2 LAST SIG_NAME P1V8_AUX_ADC_MAM
J 0
(-8010 4460);
DISPLAY 0.510638 (-8010 4460);
WIRE 16 -1 (-7700 5450)(-7700 5775);
WIRE 16 -1 (-7625 5775)(-7700 5775);
WIRE 16 -1 (-8300 5775)(-7700 5775);
FORCEPROP 0 LAST CDS_PHYS_NET_NAME P5V_ADC_MAM
J 0
(-7735 5823);
PAINT MONO (-7735 5823);
DISPLAY INVISIBLE (-7735 5823);
FORCEPROP 2 LAST SIG_NAME P5V_AUX_ADC_MAM
J 0
(-8060 5785);
DISPLAY 0.510638 (-8060 5785);
WIRE 16 -1 (-8300 5625)(-8050 5625);
FORCEPROP 2 LAST SIG_NAME P5V_AUX_ADC_TIC
J 0
(-8060 5635);
DISPLAY 0.510638 (-8060 5635);
WIRE 16 -1 (-7625 5625)(-8050 5625);
FORCEPROP 0 LAST CDS_PHYS_NET_NAME P5V_ADC_TIC
J 0
(-7760 5673);
PAINT MONO (-7760 5673);
DISPLAY INVISIBLE (-7760 5673);
WIRE 16 -1 (-8050 5450)(-8050 5625);
WIRE 16 2175 (-8575 5500)(-8075 5500);
WIRE 16 2175 (-8575 5975)(-8575 5500);
WIRE 16 2175 (-8075 5975)(-8075 5500);
WIRE 16 2175 (-8575 5975)(-8075 5975);
FORCEPROP 0 LAST M1 CO-LAYOUT
J 0
(-8475 6000);
DISPLAY 1.021277 (-8475 6000);
WIRE 16 -1 (-8500 5625)(-8625 5625);
WIRE 16 -1 (-8625 5775)(-8625 5625);
WIRE 16 -1 (-8625 5775)(-8500 5775);
WIRE 16 -1 (-9025 5775)(-8625 5775);
FORCEPROP 0 LAST CDS_PHYS_NET_NAME P5V_ADC
J 0
(-8635 5823);
PAINT MONO (-8635 5823);
DISPLAY INVISIBLE (-8635 5823);
FORCEPROP 2 LAST SIG_NAME P5V_AUX_ADC
J 0
(-8910 5775);
DISPLAY 0.510638 (-8910 5775);
FORCEPROP 2 LASTPROP $XRERR UNIQUE?
J 0
(-9150 5775);
DISPLAY 0.638298 (-9150 5775);
PAINT MONO (-9150 5775);
DISPLAY INVISIBLE (-9150 5775);
WIRE 16 -1 (-9025 5925)(-9025 5775);
WIRE 16 -1 (-9025 5775)(-9025 5575);
WIRE 16 -1 (-3775 5300)(-3775 5375);
WIRE 16 -1 (-3525 5375)(-3775 5375);
WIRE 16 -1 (-4150 5375)(-3775 5375);
WIRE 16 -1 (-4150 5300)(-4150 5375);
FORCEPROP 2 LAST SIG_NAME MAX11617_2_VREF
J 0
(-4185 5400);
DISPLAY 0.638298 (-4185 5400);
FORCEPROP 2 LASTPROP $XRERR UNIQUE?
J 0
(-4425 5400);
DISPLAY 0.638298 (-4425 5400);
PAINT MONO (-4425 5400);
DISPLAY INVISIBLE (-4425 5400);
WIRE 16 -1 (-2775 4400)(-3575 4400);
FORCEPROP 0 LAST CDS_PHYS_NET_NAME P5V_ADC_MAM
J 0
(-3085 4448);
PAINT MONO (-3085 4448);
DISPLAY INVISIBLE (-3085 4448);
FORCEPROP 2 LAST SIG_NAME P1V8_CPU0_RT_1D_ADC_MAM
J 0
(-3485 4410);
DISPLAY 0.510638 (-3485 4410);
WIRE 16 -1 (-5950 4075)(-5675 4075);
FORCEPROP 2 LAST SIG_NAME PVDD_33_S5_ADC_TIC
J 0
(-5710 4085);
DISPLAY 0.510638 (-5710 4085);
WIRE 16 -1 (-5150 4075)(-5675 4075);
FORCEPROP 0 LAST CDS_PHYS_NET_NAME P3V3_AUX_ADC_TIC
J 0
(-5285 4123);
PAINT MONO (-5285 4123);
DISPLAY INVISIBLE (-5285 4123);
WIRE 16 -1 (-5675 3925)(-5675 4075);
WIRE 16 -1 (-8450 4300)(-8550 4300);
WIRE 16 -1 (-8550 4450)(-8550 4300);
WIRE 16 -1 (-8550 4450)(-8450 4450);
FORCEPROP 0 LAST CDS_PHYS_NET_NAME P3V3_ADC
J 0
(-8435 4498);
PAINT MONO (-8435 4498);
DISPLAY INVISIBLE (-8435 4498);
WIRE 16 -1 (-8550 4450)(-8975 4450);
FORCEPROP 2 LAST SIG_NAME P1V8_AUX_ADC
J 0
(-8935 4450);
DISPLAY 0.510638 (-8935 4450);
FORCEPROP 2 LASTPROP $XRERR UNIQUE?
J 0
(-9175 4450);
DISPLAY 0.638298 (-9175 4450);
PAINT MONO (-9175 4450);
DISPLAY INVISIBLE (-9175 4450);
WIRE 16 -1 (-8975 4600)(-8975 4450);
WIRE 16 -1 (-8975 4450)(-8975 4325);
WIRE 16 -1 (-2200 2375)(-1975 2375);
WIRE 16 -1 (-2200 2550)(-2200 2375);
WIRE 16 -1 (-3425 2550)(-2200 2550);
WIRE 16 -1 (-3425 2550)(-3425 2450);
WIRE 16 -1 (-3800 2550)(-3425 2550);
WIRE 16 -1 (-3800 2550)(-3800 2450);
WIRE 16 -1 (-4125 2550)(-3800 2550);
WIRE 16 -1 (-4125 2550)(-4125 2450);
WIRE 16 -1 (-4200 2550)(-4125 2550);
FORCEPROP 2 LAST SIG_NAME P3V3_ADC128_2_VCC
J 0
(-4110 2560);
DISPLAY 0.510638 (-4110 2560);
FORCEPROP 2 LASTPROP $XRERR UNIQUE?
J 0
(-4350 2560);
DISPLAY 0.638298 (-4350 2560);
PAINT MONO (-4350 2560);
DISPLAY INVISIBLE (-4350 2560);
WIRE 16 -1 (-1975 2125)(-3425 2125);
FORCEPROP 0 LAST CDS_PHYS_NET_NAME ADC128_VREF
J 0
(-2285 2173);
PAINT MONO (-2285 2173);
DISPLAY INVISIBLE (-2285 2173);
FORCEPROP 2 LAST SIG_NAME ADC128_2_VREF
J 0
(-2635 2135);
DISPLAY 0.510638 (-2635 2135);
FORCEPROP 2 LASTPROP $XRERR UNIQUE?
J 0
(-2875 2135);
DISPLAY 0.638298 (-2875 2135);
PAINT MONO (-2875 2135);
DISPLAY INVISIBLE (-2875 2135);
WIRE 16 -1 (-3425 2250)(-3425 2125);
WIRE 16 -1 (-3425 2125)(-3425 1950);
WIRE 16 -1 (-1975 1975)(-2650 1975);
FORCEPROP 0 LAST CDS_PHYS_NET_NAME ADC128_A0
J 0
(-2285 2023);
PAINT MONO (-2285 2023);
DISPLAY INVISIBLE (-2285 2023);
FORCEPROP 2 LAST SIG_NAME ADC128_2_A0
J 0
(-2635 1985);
DISPLAY 0.510638 (-2635 1985);
WIRE 16 -1 (-1975 1875)(-2650 1875);
FORCEPROP 0 LAST CDS_PHYS_NET_NAME P12V_E1S_0_ISENSE_TIC
J 0
(-2285 1923);
PAINT MONO (-2285 1923);
DISPLAY INVISIBLE (-2285 1923);
FORCEPROP 2 LAST SIG_NAME PVDD18_S5_P1_ADC_TIC
J 0
(-2635 1885);
DISPLAY 0.510638 (-2635 1885);
WIRE 16 -1 (-1975 1825)(-2650 1825);
FORCEPROP 0 LAST CDS_PHYS_NET_NAME P3V3_PDB_AUX_ADC_TIC
J 0
(-2285 1873);
PAINT MONO (-2285 1873);
DISPLAY INVISIBLE (-2285 1873);
FORCEPROP 2 LAST SIG_NAME PVDD18_S5_P0_ADC_TIC
J 0
(-2635 1835);
DISPLAY 0.510638 (-2635 1835);
WIRE 16 -1 (-1975 1775)(-2650 1775);
FORCEPROP 0 LAST CDS_PHYS_NET_NAME P3V3_AUX_ADC_TIC
J 0
(-2285 1823);
PAINT MONO (-2285 1823);
DISPLAY INVISIBLE (-2285 1823);
FORCEPROP 2 LAST SIG_NAME PVDD_33_S5_ADC_TIC
J 0
(-2635 1785);
DISPLAY 0.510638 (-2635 1785);
WIRE 16 -1 (-1975 1725)(-2650 1725);
FORCEPROP 0 LAST CDS_PHYS_NET_NAME P3V3_ADC_TIC
J 0
(-2285 1773);
PAINT MONO (-2285 1773);
DISPLAY INVISIBLE (-2285 1773);
FORCEPROP 2 LAST SIG_NAME P1V8_CPU1_RT_1D_ADC_TIC
J 0
(-2635 1735);
DISPLAY 0.510638 (-2635 1735);
WIRE 16 -1 (-1975 1675)(-2650 1675);
FORCEPROP 0 LAST CDS_PHYS_NET_NAME P5V_ADC_TIC
J 0
(-2285 1723);
PAINT MONO (-2285 1723);
DISPLAY INVISIBLE (-2285 1723);
FORCEPROP 2 LAST SIG_NAME P1V8_CPU0_RT_1D_ADC_TIC
J 0
(-2635 1685);
DISPLAY 0.510638 (-2635 1685);
WIRE 16 -1 (-1975 1625)(-2650 1625);
FORCEPROP 0 LAST CDS_PHYS_NET_NAME P12V_OCP_V3_2_ISENSE_TIC
J 0
(-2285 1673);
PAINT MONO (-2285 1673);
DISPLAY INVISIBLE (-2285 1673);
FORCEPROP 2 LAST SIG_NAME P1V2_AUX_ADC_TIC
J 0
(-2635 1635);
DISPLAY 0.510638 (-2635 1635);
WIRE 16 -1 (-1975 1575)(-2650 1575);
FORCEPROP 0 LAST CDS_PHYS_NET_NAME P12V_OCP_SFF_ISENSE_TIC
J 0
(-2285 1623);
PAINT MONO (-2285 1623);
DISPLAY INVISIBLE (-2285 1623);
FORCEPROP 2 LAST SIG_NAME P1V8_AUX_ADC_TIC
J 0
(-2635 1585);
DISPLAY 0.510638 (-2635 1585);
WIRE 16 -1 (-1975 1525)(-2650 1525);
FORCEPROP 0 LAST CDS_PHYS_NET_NAME P12V_AUX_ADC_TIC
J 0
(-2285 1573);
PAINT MONO (-2285 1573);
DISPLAY INVISIBLE (-2285 1573);
FORCEPROP 2 LAST SIG_NAME P5V_AUX_ADC_TIC
J 0
(-2635 1535);
DISPLAY 0.510638 (-2635 1535);
WIRE 16 -1 (-3425 825)(-4500 825);
FORCEPROP 0 LAST CDS_PHYS_NET_NAME ADC128_A1
J 0
(-3810 867);
PAINT MONO (-3810 867);
DISPLAY INVISIBLE (-3810 867);
FORCEPROP 2 LAST SIG_NAME ADC128_2_A1
J 0
(-4035 835);
DISPLAY 0.553191 (-4035 835);
WIRE 16 -1 (-4500 1075)(-4500 825);
WIRE 16 -1 (-4500 825)(-4500 675);
WIRE 16 -1 (-4250 925)(-3425 925);
FORCEPROP 0 LAST CDS_PHYS_NET_NAME ADC128_A0
J 0
(-3810 967);
PAINT MONO (-3810 967);
DISPLAY INVISIBLE (-3810 967);
FORCEPROP 2 LAST SIG_NAME ADC128_2_A0
J 0
(-4035 935);
DISPLAY 0.553191 (-4035 935);
WIRE 16 -1 (-4250 1075)(-4250 925);
WIRE 16 -1 (-4250 925)(-4250 675);
WIRE 16 -1 (-2450 850)(-1600 850);
FORCEPROP 0 LAST CDS_PHYS_NET_NAME SMB_SCM_2_R4_SCL
J 0
(-2410 898);
PAINT MONO (-2410 898);
DISPLAY INVISIBLE (-2410 898);
FORCEPROP 2 LAST SIG_NAME SMB_ADC_SCL_R
J 0
(-2260 860);
DISPLAY 0.680851 (-2260 860);
WIRE 16 -1 (-2450 900)(-1600 900);
FORCEPROP 0 LAST CDS_PHYS_NET_NAME SMB_SCM_2_R4_SDA
J 0
(-2410 948);
PAINT MONO (-2410 948);
DISPLAY INVISIBLE (-2410 948);
FORCEPROP 2 LAST SIG_NAME SMB_ADC_SDA_R
J 0
(-2260 910);
DISPLAY 0.680851 (-2260 910);
WIRE 16 -1 (-500 900)(-1400 900);
FORCEPROP 0 LAST CDS_PHYS_NET_NAME SMB_SEN_TIC_3V3AUX_SDA
J 0
(-960 948);
PAINT MONO (-960 948);
DISPLAY INVISIBLE (-960 948);
FORCEPROP 2 LAST SIG_NAME SMB_SEN_TIC_2_3V3AUX_SDA
J 0
(-1085 910);
DISPLAY 0.510638 (-1085 910);
WIRE 16 -1 (-1975 2225)(-2650 2225);
FORCEPROP 0 LAST CDS_PHYS_NET_NAME SMB_SEN_TIC_3V3AUX_SDA
J 0
(-2285 2273);
PAINT MONO (-2285 2273);
DISPLAY INVISIBLE (-2285 2273);
FORCEPROP 2 LAST SIG_NAME SMB_SEN_TIC_2_3V3AUX_SDA
J 0
(-2635 2235);
DISPLAY 0.510638 (-2635 2235);
WIRE 16 -1 (-500 850)(-1400 850);
FORCEPROP 0 LAST CDS_PHYS_NET_NAME SMB_SEN_TIC_3V3AUX_SCL
J 0
(-960 898);
PAINT MONO (-960 898);
DISPLAY INVISIBLE (-960 898);
FORCEPROP 2 LAST SIG_NAME SMB_SEN_TIC_2_3V3AUX_SCL
J 0
(-1085 860);
DISPLAY 0.510638 (-1085 860);
WIRE 16 -1 (-1975 2025)(-2650 2025);
FORCEPROP 0 LAST CDS_PHYS_NET_NAME ADC128_A1
J 0
(-2285 2073);
PAINT MONO (-2285 2073);
DISPLAY INVISIBLE (-2285 2073);
FORCEPROP 2 LAST SIG_NAME ADC128_2_A1
J 0
(-2635 2035);
DISPLAY 0.510638 (-2635 2035);
WIRE 16 -1 (-500 2375)(-1175 2375);
FORCEPROP 0 LAST CDS_PHYS_NET_NAME TP_ADC128_INT
J 0
(-810 2423);
PAINT MONO (-810 2423);
DISPLAY INVISIBLE (-810 2423);
FORCEPROP 2 LAST SIG_NAME TP_ADC128_2_INT
J 0
(-1110 2385);
DISPLAY 0.510638 (-1110 2385);
FORCEPROP 2 LASTPROP $XRERR UNIQUE?
J 0
(-470 2375);
DISPLAY 0.638298 (-470 2375);
PAINT MONO (-470 2375);
DISPLAY INVISIBLE (-470 2375);
WIRE 16 -1 (-1175 4500)(-1975 4500);
FORCEPROP 0 LAST CDS_PHYS_NET_NAME P3V3_AUX_ADC_MAM
J 0
(-1485 4548);
PAINT MONO (-1485 4548);
DISPLAY INVISIBLE (-1485 4548);
FORCEPROP 2 LAST SIG_NAME PVDD_33_S5_ADC_MAM
J 0
(-1710 4510);
DISPLAY 0.510638 (-1710 4510);
WIRE 16 -1 (-1975 2275)(-2650 2275);
FORCEPROP 0 LAST CDS_PHYS_NET_NAME SMB_SEN_TIC_3V3AUX_SCL
J 0
(-2285 2323);
PAINT MONO (-2285 2323);
DISPLAY INVISIBLE (-2285 2323);
FORCEPROP 2 LAST SIG_NAME SMB_SEN_TIC_2_3V3AUX_SCL
J 0
(-2635 2285);
DISPLAY 0.510638 (-2635 2285);
WIRE 16 -1 (-2775 4700)(-3575 4700);
FORCEPROP 0 LAST CDS_PHYS_NET_NAME P12V_AUX_ADC_MAM
J 0
(-3085 4748);
PAINT MONO (-3085 4748);
DISPLAY INVISIBLE (-3085 4748);
FORCEPROP 2 LAST SIG_NAME P5V_AUX_ADC_MAM
J 0
(-3485 4710);
DISPLAY 0.510638 (-3485 4710);
WIRE 16 -1 (-2775 4600)(-3575 4600);
FORCEPROP 0 LAST CDS_PHYS_NET_NAME P12V_OCP_SFF_ISENSE_MAM
J 0
(-3085 4648);
PAINT MONO (-3085 4648);
DISPLAY INVISIBLE (-3085 4648);
FORCEPROP 2 LAST SIG_NAME P1V8_AUX_ADC_MAM
J 0
(-3485 4610);
DISPLAY 0.510638 (-3485 4610);
WIRE 16 -1 (-1150 4700)(-1975 4700);
FORCEPROP 0 LAST CDS_PHYS_NET_NAME P12V_E1S_0_ISENSE_MAM
J 0
(-1460 4748);
PAINT MONO (-1460 4748);
DISPLAY INVISIBLE (-1460 4748);
FORCEPROP 2 LAST SIG_NAME PVDD18_S5_P1_ADC_MAM
J 0
(-1710 4710);
DISPLAY 0.510638 (-1710 4710);
WIRE 16 -1 (-1150 4600)(-1975 4600);
FORCEPROP 0 LAST CDS_PHYS_NET_NAME P3V3_PDB_AUX_ADC_MAM
J 0
(-1460 4648);
PAINT MONO (-1460 4648);
DISPLAY INVISIBLE (-1460 4648);
FORCEPROP 2 LAST SIG_NAME PVDD18_S5_P0_ADC_MAM
J 0
(-1710 4610);
DISPLAY 0.510638 (-1710 4610);
DOT 1 (-7700 5775);
DOT 1 (-1075 5375);
DOT 1 (-1450 5375);
DOT 1 (-4150 6450);
DOT 1 (-2875 4800);
DOT 1 (-250 6325);
DOT 1 (-875 6450);
DOT 1 (-875 6325);
DOT 1 (-875 6200);
DOT 1 (-1525 6325);
DOT 1 (-1525 6450);
DOT 1 (-1525 6200);
DOT 1 (-2100 6450);
DOT 1 (-2100 6200);
DOT 1 (-2100 6325);
DOT 1 (-2950 6450);
DOT 1 (-2950 6200);
DOT 1 (-2950 6325);
DOT 1 (-3725 6450);
DOT 1 (-3725 6200);
DOT 1 (-3725 6325);
DOT 1 (-4150 6200);
DOT 1 (-4150 6325);
DOT 1 (-4625 6450);
DOT 1 (-4625 6325);
DOT 1 (-4625 6200);
DOT 1 (-5050 6450);
DOT 1 (-5050 6200);
DOT 1 (-5050 6325);
DOT 1 (-5500 6325);
DOT 1 (-5425 2800);
DOT 1 (-6675 1275);
DOT 1 (-8950 2975);
DOT 1 (-5250 1275);
DOT 1 (-6200 1275);
DOT 1 (-6375 2800);
DOT 1 (-6850 2800);
DOT 1 (-5775 2650);
DOT 1 (-5200 4225);
DOT 1 (-6750 4225);
DOT 1 (-6150 5750);
DOT 1 (-6800 5750);
DOT 1 (-8975 4450);
DOT 1 (-9025 1375);
DOT 1 (-8425 1375);
DOT 1 (-4500 825);
DOT 1 (-4500 1450);
DOT 1 (-4125 2550);
DOT 1 (-3425 2550);
DOT 1 (-3775 5375);
DOT 1 (-7975 4300);
DOT 1 (-8550 4450);
DOT 1 (-9025 5775);
DOT 1 (-7625 4450);
DOT 1 (-7525 2975);
DOT 1 (-8475 2975);
DOT 1 (-5675 4075);
DOT 1 (-7300 1375);
DOT 1 (-3425 2125);
DOT 1 (-3800 2550);
DOT 1 (-4250 925);
DOT 1 (-8625 5775);
DOT 1 (-7875 2825);
DOT 1 (-7825 1225);
DOT 1 (-4950 5750);
DOT 1 (-5550 5600);
DOT 1 (-5600 1125);
DOT 1 (-8050 5625);
DOT 1 (-6275 4225);
DOT 1 (-2875 4900);
FORCENOTE
1.402V
(-1350 6250) 0;
DISPLAY LEFT (-1350 6250);
DISPLAY 1.021277 (-1350 6250);
PAINT WHITE (-1350 6250);
FORCENOTE
PVDD18_S5_P0
(-1475 6375) 0;
DISPLAY LEFT (-1475 6375);
DISPLAY 1.021277 (-1475 6375);
PAINT WHITE (-1475 6375);
FORCENOTE
P1V8_CPU1_RT_1D
(-2900 6375) 0;
DISPLAY LEFT (-2900 6375);
DISPLAY 1.021277 (-2900 6375);
PAINT WHITE (-2900 6375);
FORCENOTE
0.934V
(-4075 6250) 0;
DISPLAY LEFT (-4075 6250);
DISPLAY 1.021277 (-4075 6250);
PAINT WHITE (-4075 6250);
FORCENOTE
1.402V
(-4525 6250) 0;
DISPLAY LEFT (-4525 6250);
DISPLAY 1.021277 (-4525 6250);
PAINT WHITE (-4525 6250);
FORCENOTE
PVDD_33_S5
(-2025 6375) 0;
DISPLAY LEFT (-2025 6375);
DISPLAY 1.021277 (-2025 6375);
PAINT WHITE (-2025 6375);
FORCENOTE
1.581V
(-1950 6250) 0;
DISPLAY LEFT (-1950 6250);
DISPLAY 1.021277 (-1950 6250);
PAINT WHITE (-1950 6250);
FORCENOTE
1.402V
(-2750 6250) 0;
DISPLAY LEFT (-2750 6250);
DISPLAY 1.021277 (-2750 6250);
PAINT WHITE (-2750 6250);
FORCENOTE
P1V8_CPU0_RT_1D
(-3675 6375) 0;
DISPLAY LEFT (-3675 6375);
DISPLAY 1.021277 (-3675 6375);
PAINT WHITE (-3675 6375);
FORCENOTE
1.402V
(-3475 6250) 0;
DISPLAY LEFT (-3475 6250);
DISPLAY 1.021277 (-3475 6250);
PAINT WHITE (-3475 6250);
FORCENOTE
P1V2_AUX
(-4125 6375) 0;
DISPLAY LEFT (-4125 6375);
DISPLAY 1.021277 (-4125 6375);
PAINT WHITE (-4125 6375);
FORCENOTE
IF USE AD128,POP R3668,R3670
(-3925 675) 0;
DISPLAY LEFT (-3925 675);
DISPLAY 0.808511 (-3925 675);
PAINT WHITE (-3925 675);
FORCENOTE
ADDR: 0X3A(8-BIT) / 0X1D(7-BIT)
(-3350 1125) 0;
DISPLAY LEFT (-3350 1125);
DISPLAY 1.595745 (-3350 1125);
PAINT WHITE (-3350 1125);
FORCENOTE
P1V8_AUX
(-4575 6375) 0;
DISPLAY LEFT (-4575 6375);
DISPLAY 1.021277 (-4575 6375);
PAINT WHITE (-4575 6375);
FORCENOTE
1.677V
(-5000 6250) 0;
DISPLAY LEFT (-5000 6250);
DISPLAY 1.021277 (-5000 6250);
PAINT WHITE (-5000 6250);
FORCENOTE
P5V_AUX
(-5000 6375) 0;
DISPLAY LEFT (-5000 6375);
DISPLAY 1.021277 (-5000 6375);
PAINT WHITE (-5000 6375);
FORCENOTE
V SOURCE
(-5450 6350) 0;
DISPLAY LEFT (-5450 6350);
DISPLAY 1.021277 (-5450 6350);
PAINT WHITE (-5450 6350);
FORCENOTE
VIN
(-5350 6250) 0;
DISPLAY LEFT (-5350 6250);
DISPLAY 1.021277 (-5350 6250);
PAINT WHITE (-5350 6250);
FORCENOTE
ADDR: 0X6A(8-BIT) / 0X35(7-BIT)
(-3525 3875) 0;
DISPLAY LEFT (-3525 3875);
DISPLAY 1.595745 (-3525 3875);
PAINT WHITE (-3525 3875);
FORCENOTE
PVDD18_S5_P1
(-825 6375) 0;
DISPLAY LEFT (-825 6375);
DISPLAY 1.021277 (-825 6375);
PAINT WHITE (-825 6375);
FORCENOTE
1.402V
(-725 6250) 0;
DISPLAY LEFT (-725 6250);
DISPLAY 1.021277 (-725 6250);
PAINT WHITE (-725 6250);
QUIT
